FILE_TYPE = MACRO_DRAWING;
SET COLOR_WIRE YELLOW;
SET COLOR_PROP ORANGE;
SET COLOR_DOT WHITE;
SET COLOR_ARC YELLOW;
SET COLOR_BODY GREEN;
SET COLOR_NOTE PURPLE;
SET PROP_DISPLAY VALUE;
SET PAGE_NUMBER P454;
FORCEADD Q_CAP..1
(-6925 4325);
FORCEPROP 1 LAST LOCATION C369
J 0
(-6875 4425);
DISPLAY 0.638298 (-6875 4425);
PAINT WHITE (-6875 4425);
FORCEPROP 0 LAST $SEC 1
J 0
(-6875 4450);
DISPLAY 0.680851 (-6875 4450);
PAINT MONO (-6875 4450);
DISPLAY INVISIBLE (-6875 4450);
FORCEPROP 0 LAST CDS_SEC 1
J 0
(-6875 4450);
DISPLAY 0.680851 (-6875 4450);
DISPLAY INVISIBLE (-6875 4450);
FORCEPROP 1 LASTPIN (-6925 4425) $PN 1
J 0
(-6915 4405);
DISPLAY 0.787234 (-6915 4405);
PAINT MONO (-6915 4405);
FORCEPROP 1 LASTPIN (-6925 4225) $PN 2
J 0
(-6915 4205);
DISPLAY 0.787234 (-6915 4205);
PAINT MONO (-6915 4205);
FORCEPROP 1 LAST MATERIAL X6S
J 0
(-6875 4225);
DISPLAY 0.510638 (-6875 4225);
FORCEPROP 1 LAST VOLTAGE 4V
J 0
(-6875 4325);
DISPLAY 0.510638 (-6875 4325);
FORCEPROP 1 LAST TOLERANCE 20%
J 0
(-6875 4275);
DISPLAY 0.510638 (-6875 4275);
FORCEPROP 1 LAST PACK_TYPE C0402
J 0
(-6875 4175);
DISPLAY 0.510638 (-6875 4175);
FORCEPROP 1 LAST VALUE 22UF
J 0
(-6875 4375);
DISPLAY 0.510638 (-6875 4375);
FORCEPROP 2 LAST CDS_LIB pure_quanta
J 0
(-6925 4325);
DISPLAY INVISIBLE (-6925 4325);
FORCEPROP 1 LAST PATH I10
J 0
(-6875 4475);
DISPLAY 0.978723 (-6875 4475);
PAINT WHITE (-6875 4475);
DISPLAY INVISIBLE (-6875 4475);
FORCEPROP 1 LAST PART_NUMBER CH622KMEB02
J 0
(-6875 4175);
DISPLAY 0.978723 (-6875 4175);
DISPLAY INVISIBLE (-6875 4175);
FORCEADD Q_CAP..1
(-425 2400);
FORCEPROP 1 LAST LOCATION C7028
J 0
(-375 2500);
DISPLAY 0.638298 (-375 2500);
FORCEPROP 0 LAST $SEC 1
J 0
(-375 2550);
DISPLAY 0.680851 (-375 2550);
PAINT MONO (-375 2550);
DISPLAY INVISIBLE (-375 2550);
FORCEPROP 0 LAST CDS_SEC 1
J 0
(-375 2550);
DISPLAY 0.680851 (-375 2550);
DISPLAY INVISIBLE (-375 2550);
FORCEPROP 1 LASTPIN (-425 2500) $PN 1
J 0
(-415 2480);
DISPLAY 0.787234 (-415 2480);
PAINT MONO (-415 2480);
FORCEPROP 1 LASTPIN (-425 2300) $PN 2
J 0
(-415 2280);
DISPLAY 0.787234 (-415 2280);
PAINT MONO (-415 2280);
FORCEPROP 1 LAST VOLTAGE 4V
J 0
(-375 2400);
DISPLAY 0.638298 (-375 2400);
FORCEPROP 1 LAST VALUE 100UF
J 0
(-375 2450);
DISPLAY 0.638298 (-375 2450);
FORCEPROP 1 LAST PACK_TYPE C0805
J 0
(-375 2200);
DISPLAY 0.638298 (-375 2200);
FORCEPROP 1 LAST MATERIAL X6S
J 0
(-375 2300);
DISPLAY 0.638298 (-375 2300);
FORCEPROP 1 LAST TOLERANCE 20%
J 0
(-375 2350);
DISPLAY 0.638298 (-375 2350);
FORCEPROP 2 LAST CDS_LIB pure_quanta
J 0
(-425 2400);
DISPLAY INVISIBLE (-425 2400);
FORCEPROP 1 LAST PATH I100
J 0
(-375 2550);
DISPLAY 0.978723 (-375 2550);
PAINT WHITE (-375 2550);
DISPLAY INVISIBLE (-375 2550);
FORCEPROP 1 LAST PART_NUMBER CH710KMEA01
J 0
(-375 2250);
DISPLAY 0.638298 (-375 2250);
DISPLAY INVISIBLE (-375 2250);
FORCEADD Q_CAPP..1
(-1575 5000);
FORCEPROP 1 LAST LOCATION C7037
J 0
(-1525 5100);
DISPLAY 0.638298 (-1525 5100);
FORCEPROP 0 LAST $SEC 1
J 0
(-1525 5150);
DISPLAY 0.680851 (-1525 5150);
PAINT MONO (-1525 5150);
DISPLAY INVISIBLE (-1525 5150);
FORCEPROP 0 LAST CDS_SEC 1
J 0
(-1525 5150);
DISPLAY 0.680851 (-1525 5150);
DISPLAY INVISIBLE (-1525 5150);
FORCEPROP 1 LASTPIN (-1575 5100) $PN 1
J 0
(-1565 5085);
DISPLAY 0.787234 (-1565 5085);
PAINT MONO (-1565 5085);
FORCEPROP 1 LASTPIN (-1575 4900) $PN 2
J 0
(-1565 4885);
DISPLAY 0.787234 (-1565 4885);
PAINT MONO (-1565 4885);
FORCEPROP 1 LAST PACK_TYPE SMLF
J 0
(-1525 4850);
DISPLAY 0.510638 (-1525 4850);
FORCEPROP 1 LAST MATERIAL SPCAP
J 0
(-1525 4900);
DISPLAY 0.510638 (-1525 4900);
FORCEPROP 1 LAST VALUE 470UF
J 0
(-1525 5050);
DISPLAY 0.510638 (-1525 5050);
FORCEPROP 1 LAST TOLERANCE 20%
J 0
(-1525 5000);
DISPLAY 0.510638 (-1525 5000);
FORCEPROP 1 LAST VOLTAGE 2.5V
J 0
(-1525 4950);
DISPLAY 0.510638 (-1525 4950);
FORCEPROP 2 LAST CDS_LIB pure_quanta
J 0
(-1575 5000);
DISPLAY INVISIBLE (-1575 5000);
FORCEPROP 1 LAST PATH I101
J 0
(-1525 5150);
DISPLAY 0.978723 (-1525 5150);
DISPLAY INVISIBLE (-1525 5150);
FORCEPROP 1 LAST PART_NUMBER CH747LM8818
J 0
(-1525 4800);
DISPLAY 0.404255 (-1525 4800);
DISPLAY INVISIBLE (-1525 4800);
FORCEADD Q_CAP..1
(-1275 5000);
FORCEPROP 1 LAST LOCATION C7038
J 0
(-1225 5100);
DISPLAY 0.638298 (-1225 5100);
FORCEPROP 0 LAST $SEC 1
J 0
(-1225 5150);
DISPLAY 0.680851 (-1225 5150);
PAINT MONO (-1225 5150);
DISPLAY INVISIBLE (-1225 5150);
FORCEPROP 0 LAST CDS_SEC 1
J 0
(-1225 5150);
DISPLAY 0.680851 (-1225 5150);
DISPLAY INVISIBLE (-1225 5150);
FORCEPROP 1 LASTPIN (-1275 5100) $PN 1
J 0
(-1265 5080);
DISPLAY 0.787234 (-1265 5080);
PAINT MONO (-1265 5080);
FORCEPROP 1 LASTPIN (-1275 4900) $PN 2
J 0
(-1265 4880);
DISPLAY 0.787234 (-1265 4880);
PAINT MONO (-1265 4880);
FORCEPROP 1 LAST PACK_TYPE C0805
J 0
(-1225 4800);
DISPLAY 0.638298 (-1225 4800);
FORCEPROP 1 LAST MATERIAL X6S
J 0
(-1225 4900);
DISPLAY 0.638298 (-1225 4900);
FORCEPROP 1 LAST VALUE 47UF
J 0
(-1225 5050);
DISPLAY 0.638298 (-1225 5050);
FORCEPROP 1 LAST VOLTAGE 4V
J 0
(-1225 5000);
DISPLAY 0.638298 (-1225 5000);
FORCEPROP 1 LAST TOLERANCE 20%
J 0
(-1225 4950);
DISPLAY 0.638298 (-1225 4950);
FORCEPROP 2 LAST CDS_LIB pure_quanta
J 0
(-1275 5000);
DISPLAY INVISIBLE (-1275 5000);
FORCEPROP 1 LAST PATH I102
J 0
(-1225 5150);
DISPLAY 0.978723 (-1225 5150);
PAINT WHITE (-1225 5150);
DISPLAY INVISIBLE (-1225 5150);
FORCEPROP 1 LAST PART_NUMBER CH647KMEA04
J 0
(-1225 4850);
DISPLAY 0.638298 (-1225 4850);
DISPLAY INVISIBLE (-1225 4850);
FORCEADD Q_CAP..1
(-1025 5000);
FORCEPROP 1 LAST LOCATION C7039
J 0
(-975 5100);
DISPLAY 0.638298 (-975 5100);
FORCEPROP 0 LAST $SEC 1
J 0
(-975 5150);
DISPLAY 0.680851 (-975 5150);
PAINT MONO (-975 5150);
DISPLAY INVISIBLE (-975 5150);
FORCEPROP 0 LAST CDS_SEC 1
J 0
(-975 5150);
DISPLAY 0.680851 (-975 5150);
DISPLAY INVISIBLE (-975 5150);
FORCEPROP 1 LASTPIN (-1025 5100) $PN 1
J 0
(-1015 5080);
DISPLAY 0.787234 (-1015 5080);
PAINT MONO (-1015 5080);
FORCEPROP 1 LASTPIN (-1025 4900) $PN 2
J 0
(-1015 4880);
DISPLAY 0.787234 (-1015 4880);
PAINT MONO (-1015 4880);
FORCEPROP 1 LAST MATERIAL X6S
J 0
(-975 4900);
DISPLAY 0.638298 (-975 4900);
FORCEPROP 1 LAST PACK_TYPE C0805
J 0
(-975 4800);
DISPLAY 0.638298 (-975 4800);
FORCEPROP 1 LAST VOLTAGE 4V
J 0
(-975 5000);
DISPLAY 0.638298 (-975 5000);
FORCEPROP 1 LAST VALUE 47UF
J 0
(-975 5050);
DISPLAY 0.638298 (-975 5050);
FORCEPROP 1 LAST TOLERANCE 20%
J 0
(-975 4950);
DISPLAY 0.638298 (-975 4950);
FORCEPROP 2 LAST CDS_LIB pure_quanta
J 0
(-1025 5000);
DISPLAY INVISIBLE (-1025 5000);
FORCEPROP 1 LAST PATH I103
J 0
(-975 5150);
DISPLAY 0.978723 (-975 5150);
PAINT WHITE (-975 5150);
DISPLAY INVISIBLE (-975 5150);
FORCEPROP 1 LAST PART_NUMBER CH647KMEA04
J 0
(-975 4850);
DISPLAY 0.638298 (-975 4850);
DISPLAY INVISIBLE (-975 4850);
FORCEADD Q_CAP..1
(-800 5000);
FORCEPROP 1 LAST LOCATION C7040
J 0
(-750 5100);
DISPLAY 0.638298 (-750 5100);
FORCEPROP 0 LAST $SEC 1
J 0
(-750 5150);
DISPLAY 0.680851 (-750 5150);
PAINT MONO (-750 5150);
DISPLAY INVISIBLE (-750 5150);
FORCEPROP 0 LAST CDS_SEC 1
J 0
(-750 5150);
DISPLAY 0.680851 (-750 5150);
DISPLAY INVISIBLE (-750 5150);
FORCEPROP 1 LASTPIN (-800 5100) $PN 1
J 0
(-790 5080);
DISPLAY 0.787234 (-790 5080);
PAINT MONO (-790 5080);
FORCEPROP 1 LASTPIN (-800 4900) $PN 2
J 0
(-790 4880);
DISPLAY 0.787234 (-790 4880);
PAINT MONO (-790 4880);
FORCEPROP 1 LAST MATERIAL X6S
J 0
(-750 4900);
DISPLAY 0.638298 (-750 4900);
FORCEPROP 1 LAST PACK_TYPE C0805
J 0
(-750 4800);
DISPLAY 0.638298 (-750 4800);
FORCEPROP 1 LAST TOLERANCE 20%
J 0
(-750 4950);
DISPLAY 0.638298 (-750 4950);
FORCEPROP 1 LAST VALUE 47UF
J 0
(-750 5050);
DISPLAY 0.638298 (-750 5050);
FORCEPROP 1 LAST VOLTAGE 4V
J 0
(-750 5000);
DISPLAY 0.638298 (-750 5000);
FORCEPROP 2 LAST CDS_LIB pure_quanta
J 0
(-800 5000);
DISPLAY INVISIBLE (-800 5000);
FORCEPROP 1 LAST PATH I104
J 0
(-750 5150);
DISPLAY 0.978723 (-750 5150);
PAINT WHITE (-750 5150);
DISPLAY INVISIBLE (-750 5150);
FORCEPROP 1 LAST PART_NUMBER CH647KMEA04
J 0
(-750 4850);
DISPLAY 0.638298 (-750 4850);
DISPLAY INVISIBLE (-750 4850);
FORCEADD Q_CAP..1
(-550 5000);
FORCEPROP 1 LAST LOCATION C7041
J 0
(-500 5100);
DISPLAY 0.638298 (-500 5100);
FORCEPROP 0 LAST $SEC 1
J 0
(-500 5150);
DISPLAY 0.680851 (-500 5150);
PAINT MONO (-500 5150);
DISPLAY INVISIBLE (-500 5150);
FORCEPROP 0 LAST CDS_SEC 1
J 0
(-500 5150);
DISPLAY 0.680851 (-500 5150);
DISPLAY INVISIBLE (-500 5150);
FORCEPROP 1 LASTPIN (-550 5100) $PN 1
J 0
(-540 5080);
DISPLAY 0.787234 (-540 5080);
PAINT MONO (-540 5080);
FORCEPROP 1 LASTPIN (-550 4900) $PN 2
J 0
(-540 4880);
DISPLAY 0.787234 (-540 4880);
PAINT MONO (-540 4880);
FORCEPROP 1 LAST VALUE 47UF
J 0
(-500 5050);
DISPLAY 0.638298 (-500 5050);
FORCEPROP 1 LAST MATERIAL X6S
J 0
(-500 4900);
DISPLAY 0.638298 (-500 4900);
FORCEPROP 1 LAST PACK_TYPE C0805
J 0
(-500 4800);
DISPLAY 0.638298 (-500 4800);
FORCEPROP 1 LAST TOLERANCE 20%
J 0
(-500 4950);
DISPLAY 0.638298 (-500 4950);
FORCEPROP 1 LAST VOLTAGE 4V
J 0
(-500 5000);
DISPLAY 0.638298 (-500 5000);
FORCEPROP 2 LAST CDS_LIB pure_quanta
J 0
(-550 5000);
DISPLAY INVISIBLE (-550 5000);
FORCEPROP 1 LAST PATH I105
J 0
(-500 5150);
DISPLAY 0.978723 (-500 5150);
PAINT WHITE (-500 5150);
DISPLAY INVISIBLE (-500 5150);
FORCEPROP 1 LAST PART_NUMBER CH647KMEA04
J 0
(-500 4850);
DISPLAY 0.638298 (-500 4850);
DISPLAY INVISIBLE (-500 4850);
FORCEADD Q_CAP..1
(-6725 4325);
FORCEPROP 1 LAST LOCATION C372
J 0
(-6675 4425);
DISPLAY 0.808511 (-6675 4425);
PAINT WHITE (-6675 4425);
FORCEPROP 0 LAST $SEC 1
J 0
(-6675 4475);
DISPLAY 0.680851 (-6675 4475);
PAINT MONO (-6675 4475);
DISPLAY INVISIBLE (-6675 4475);
FORCEPROP 0 LAST CDS_SEC 1
J 0
(-6675 4475);
DISPLAY 0.680851 (-6675 4475);
DISPLAY INVISIBLE (-6675 4475);
FORCEPROP 1 LASTPIN (-6725 4425) $PN 1
J 0
(-6715 4405);
DISPLAY 0.787234 (-6715 4405);
PAINT MONO (-6715 4405);
FORCEPROP 1 LASTPIN (-6725 4225) $PN 2
J 0
(-6715 4205);
DISPLAY 0.787234 (-6715 4205);
PAINT MONO (-6715 4205);
FORCEPROP 1 LAST TOLERANCE 20%
J 0
(-6675 4275);
DISPLAY 0.510638 (-6675 4275);
FORCEPROP 1 LAST VOLTAGE 6.3V
J 0
(-6675 4325);
DISPLAY 0.510638 (-6675 4325);
FORCEPROP 1 LAST VALUE 10UF
J 0
(-6675 4375);
DISPLAY 0.510638 (-6675 4375);
FORCEPROP 1 LAST MATERIAL X6S
J 0
(-6675 4225);
DISPLAY 0.510638 (-6675 4225);
FORCEPROP 1 LAST PACK_TYPE C0402
J 0
(-6675 4175);
DISPLAY 0.510638 (-6675 4175);
FORCEPROP 2 LAST CDS_LIB pure_quanta
J 0
(-6725 4325);
DISPLAY INVISIBLE (-6725 4325);
FORCEPROP 1 LAST PATH I11
J 0
(-6675 4475);
DISPLAY 0.978723 (-6675 4475);
PAINT WHITE (-6675 4475);
DISPLAY INVISIBLE (-6675 4475);
FORCEPROP 1 LAST PART_NUMBER CH6101MEB01
J 0
(-6675 4175);
DISPLAY 0.978723 (-6675 4175);
DISPLAY INVISIBLE (-6675 4175);
FORCEADD Q_CAP..1
(-6525 4325);
FORCEPROP 1 LAST LOCATION C371
J 0
(-6475 4425);
DISPLAY 0.638298 (-6475 4425);
PAINT WHITE (-6475 4425);
FORCEPROP 0 LAST $SEC 1
J 0
(-6475 4450);
DISPLAY 0.680851 (-6475 4450);
PAINT MONO (-6475 4450);
DISPLAY INVISIBLE (-6475 4450);
FORCEPROP 0 LAST CDS_SEC 1
J 0
(-6475 4450);
DISPLAY 0.680851 (-6475 4450);
DISPLAY INVISIBLE (-6475 4450);
FORCEPROP 1 LASTPIN (-6525 4425) $PN 1
J 0
(-6515 4405);
DISPLAY 0.787234 (-6515 4405);
PAINT MONO (-6515 4405);
FORCEPROP 1 LASTPIN (-6525 4225) $PN 2
J 0
(-6515 4205);
DISPLAY 0.787234 (-6515 4205);
PAINT MONO (-6515 4205);
FORCEPROP 1 LAST VALUE 4.7UF
J 0
(-6475 4375);
DISPLAY 0.510638 (-6475 4375);
FORCEPROP 1 LAST VOLTAGE 6.3V
J 0
(-6475 4325);
DISPLAY 0.510638 (-6475 4325);
FORCEPROP 1 LAST TOLERANCE 20%
J 0
(-6475 4275);
DISPLAY 0.510638 (-6475 4275);
FORCEPROP 1 LAST MATERIAL X6S
J 0
(-6475 4225);
DISPLAY 0.510638 (-6475 4225);
FORCEPROP 1 LAST PACK_TYPE 0402
J 0
(-6475 4175);
DISPLAY 0.510638 (-6475 4175);
FORCEPROP 2 LAST CDS_LIB pure_quanta
J 0
(-6525 4325);
DISPLAY INVISIBLE (-6525 4325);
FORCEPROP 1 LAST PATH I12
J 0
(-6475 4475);
DISPLAY 0.978723 (-6475 4475);
PAINT WHITE (-6475 4475);
DISPLAY INVISIBLE (-6475 4475);
FORCEPROP 1 LAST PART_NUMBER CH5471MEB01
J 0
(-6475 4175);
DISPLAY 0.978723 (-6475 4175);
DISPLAY INVISIBLE (-6475 4175);
FORCEADD Q_CAP..1
(-6300 4325);
FORCEPROP 1 LAST LOCATION C374
J 0
(-6250 4425);
DISPLAY 0.808511 (-6250 4425);
PAINT WHITE (-6250 4425);
FORCEPROP 0 LAST $SEC 1
J 0
(-6250 4475);
DISPLAY 0.680851 (-6250 4475);
PAINT MONO (-6250 4475);
DISPLAY INVISIBLE (-6250 4475);
FORCEPROP 0 LAST CDS_SEC 1
J 0
(-6250 4475);
DISPLAY 0.680851 (-6250 4475);
DISPLAY INVISIBLE (-6250 4475);
FORCEPROP 1 LASTPIN (-6300 4425) $PN 1
J 0
(-6290 4405);
DISPLAY 0.787234 (-6290 4405);
PAINT MONO (-6290 4405);
FORCEPROP 1 LASTPIN (-6300 4225) $PN 2
J 0
(-6290 4205);
DISPLAY 0.787234 (-6290 4205);
PAINT MONO (-6290 4205);
FORCEPROP 1 LAST TOLERANCE 20%
J 0
(-6250 4275);
DISPLAY 0.510638 (-6250 4275);
FORCEPROP 1 LAST VOLTAGE 4V
J 0
(-6250 4325);
DISPLAY 0.510638 (-6250 4325);
FORCEPROP 1 LAST VALUE 1UF
J 0
(-6250 4375);
DISPLAY 0.510638 (-6250 4375);
FORCEPROP 1 LAST MATERIAL X6S
J 0
(-6250 4225);
DISPLAY 0.510638 (-6250 4225);
FORCEPROP 1 LAST PACK_TYPE 0201
J 0
(-6250 4175);
DISPLAY 0.510638 (-6250 4175);
FORCEPROP 2 LAST CDS_LIB pure_quanta
J 0
(-6300 4325);
DISPLAY INVISIBLE (-6300 4325);
FORCEPROP 1 LAST PATH I13
J 0
(-6250 4475);
DISPLAY 0.978723 (-6250 4475);
PAINT WHITE (-6250 4475);
DISPLAY INVISIBLE (-6250 4475);
FORCEPROP 1 LAST PART_NUMBER CH-10KMEE00
J 0
(-6250 4175);
DISPLAY 0.510638 (-6250 4175);
DISPLAY INVISIBLE (-6250 4175);
FORCEADD UNIVERSAL_GND..1
(-6100 4000);
FORCEPROP 3 LASTPIN (-6100 4050) SIG_NAME GND\g
J 0
(-6090 4060);
DISPLAY 0.659574 (-6090 4060);
PAINT MONO (-6090 4060);
DISPLAY INVISIBLE (-6090 4060);
FORCEPROP 2 LAST CDS_LIB pure_quanta_power
J 0
(-6100 4000);
DISPLAY INVISIBLE (-6100 4000);
FORCEPROP 1 LAST HDL_POWER GND
J 1
(-6075 3925);
DISPLAY 0.872340 (-6075 3925);
PAINT GREEN (-6075 3925);
DISPLAY INVISIBLE (-6075 3925);
FORCEPROP 1 LAST PATH I14
J 0
(-6025 4000);
DISPLAY 0.872340 (-6025 4000);
PAINT AQUA (-6025 4000);
DISPLAY INVISIBLE (-6025 4000);
FORCEADD Q_CAP..1
(-6100 4325);
FORCEPROP 1 LAST LOCATION C376
J 0
(-6050 4425);
DISPLAY 0.808511 (-6050 4425);
PAINT WHITE (-6050 4425);
FORCEPROP 0 LAST $SEC 1
J 0
(-6050 4475);
DISPLAY 0.680851 (-6050 4475);
PAINT MONO (-6050 4475);
DISPLAY INVISIBLE (-6050 4475);
FORCEPROP 0 LAST CDS_SEC 1
J 0
(-6050 4475);
DISPLAY 0.680851 (-6050 4475);
DISPLAY INVISIBLE (-6050 4475);
FORCEPROP 1 LASTPIN (-6100 4425) $PN 1
J 0
(-6090 4405);
DISPLAY 0.787234 (-6090 4405);
PAINT MONO (-6090 4405);
FORCEPROP 1 LASTPIN (-6100 4225) $PN 2
J 0
(-6090 4205);
DISPLAY 0.787234 (-6090 4205);
PAINT MONO (-6090 4205);
FORCEPROP 1 LAST PACK_TYPE 0201
J 0
(-6050 4175);
DISPLAY 0.510638 (-6050 4175);
FORCEPROP 1 LAST MATERIAL X6S
J 0
(-6050 4225);
DISPLAY 0.510638 (-6050 4225);
FORCEPROP 1 LAST TOLERANCE 20%
J 0
(-6050 4275);
DISPLAY 0.510638 (-6050 4275);
FORCEPROP 1 LAST VALUE 1UF
J 0
(-6050 4375);
DISPLAY 0.510638 (-6050 4375);
FORCEPROP 1 LAST VOLTAGE 4V
J 0
(-6050 4325);
DISPLAY 0.510638 (-6050 4325);
FORCEPROP 2 LAST CDS_LIB pure_quanta
J 0
(-6100 4325);
DISPLAY INVISIBLE (-6100 4325);
FORCEPROP 1 LAST PATH I15
J 0
(-6050 4475);
DISPLAY 0.978723 (-6050 4475);
PAINT WHITE (-6050 4475);
DISPLAY INVISIBLE (-6050 4475);
FORCEPROP 1 LAST PART_NUMBER CH-10KMEE00
J 0
(-6050 4175);
DISPLAY 0.510638 (-6050 4175);
DISPLAY INVISIBLE (-6050 4175);
FORCEADD Q_CAP..1
(-5875 4325);
FORCEPROP 1 LAST LOCATION C377
J 0
(-5825 4425);
DISPLAY 0.978723 (-5825 4425);
PAINT WHITE (-5825 4425);
FORCEPROP 0 LAST $SEC 1
J 0
(-5825 4475);
DISPLAY 0.680851 (-5825 4475);
PAINT MONO (-5825 4475);
DISPLAY INVISIBLE (-5825 4475);
FORCEPROP 0 LAST CDS_SEC 1
J 0
(-5825 4475);
DISPLAY 0.680851 (-5825 4475);
DISPLAY INVISIBLE (-5825 4475);
FORCEPROP 1 LASTPIN (-5875 4425) $PN 1
J 0
(-5865 4405);
DISPLAY 0.787234 (-5865 4405);
PAINT MONO (-5865 4405);
FORCEPROP 1 LASTPIN (-5875 4225) $PN 2
J 0
(-5865 4205);
DISPLAY 0.787234 (-5865 4205);
PAINT MONO (-5865 4205);
FORCEPROP 1 LAST VALUE 0.1UF
J 0
(-5825 4375);
DISPLAY 0.638298 (-5825 4375);
FORCEPROP 1 LAST VOLTAGE 10V
J 0
(-5825 4325);
DISPLAY 0.638298 (-5825 4325);
FORCEPROP 1 LAST TOLERANCE 10%
J 0
(-5825 4275);
DISPLAY 0.638298 (-5825 4275);
FORCEPROP 1 LAST MATERIAL X7S
J 0
(-5825 4225);
DISPLAY 0.638298 (-5825 4225);
FORCEPROP 1 LAST PACK_TYPE C0201
J 0
(-5825 4175);
DISPLAY 0.638298 (-5825 4175);
FORCEPROP 2 LAST CDS_LIB pure_quanta
J 0
(-5875 4325);
DISPLAY INVISIBLE (-5875 4325);
FORCEPROP 1 LAST PATH I16
J 0
(-5825 4475);
DISPLAY 0.978723 (-5825 4475);
PAINT WHITE (-5825 4475);
DISPLAY INVISIBLE (-5825 4475);
FORCEPROP 1 LAST PART_NUMBER CH4102K6E00
J 0
(-5825 4175);
DISPLAY 0.978723 (-5825 4175);
DISPLAY INVISIBLE (-5825 4175);
FORCEADD Q_CAP..1
(-5625 4325);
FORCEPROP 1 LAST LOCATION C379
J 0
(-5575 4425);
DISPLAY 0.978723 (-5575 4425);
PAINT WHITE (-5575 4425);
FORCEPROP 0 LAST $SEC 1
J 0
(-5575 4475);
DISPLAY 0.680851 (-5575 4475);
PAINT MONO (-5575 4475);
DISPLAY INVISIBLE (-5575 4475);
FORCEPROP 0 LAST CDS_SEC 1
J 0
(-5575 4475);
DISPLAY 0.680851 (-5575 4475);
DISPLAY INVISIBLE (-5575 4475);
FORCEPROP 1 LASTPIN (-5625 4425) $PN 1
J 0
(-5615 4405);
DISPLAY 0.787234 (-5615 4405);
PAINT MONO (-5615 4405);
FORCEPROP 1 LASTPIN (-5625 4225) $PN 2
J 0
(-5615 4205);
DISPLAY 0.787234 (-5615 4205);
PAINT MONO (-5615 4205);
FORCEPROP 1 LAST TOLERANCE 10%
J 0
(-5575 4275);
DISPLAY 0.638298 (-5575 4275);
FORCEPROP 1 LAST VOLTAGE 10V
J 0
(-5575 4325);
DISPLAY 0.638298 (-5575 4325);
FORCEPROP 1 LAST VALUE 0.1UF
J 0
(-5575 4375);
DISPLAY 0.638298 (-5575 4375);
FORCEPROP 1 LAST MATERIAL X7S
J 0
(-5575 4225);
DISPLAY 0.638298 (-5575 4225);
FORCEPROP 1 LAST PACK_TYPE C0201
J 0
(-5575 4175);
DISPLAY 0.638298 (-5575 4175);
FORCEPROP 2 LAST CDS_LIB pure_quanta
J 0
(-5625 4325);
DISPLAY INVISIBLE (-5625 4325);
FORCEPROP 1 LAST PATH I17
J 0
(-5575 4475);
DISPLAY 0.978723 (-5575 4475);
PAINT WHITE (-5575 4475);
DISPLAY INVISIBLE (-5575 4475);
FORCEPROP 1 LAST PART_NUMBER CH4102K6E00
J 0
(-5575 4175);
DISPLAY 0.978723 (-5575 4175);
DISPLAY INVISIBLE (-5575 4175);
FORCEADD Q_CAP..1
(-5375 4325);
FORCEPROP 1 LAST LOCATION C380
J 0
(-5325 4425);
DISPLAY 0.978723 (-5325 4425);
PAINT WHITE (-5325 4425);
FORCEPROP 0 LAST $SEC 1
J 0
(-5325 4475);
DISPLAY 0.680851 (-5325 4475);
PAINT MONO (-5325 4475);
DISPLAY INVISIBLE (-5325 4475);
FORCEPROP 0 LAST CDS_SEC 1
J 0
(-5325 4475);
DISPLAY 0.680851 (-5325 4475);
DISPLAY INVISIBLE (-5325 4475);
FORCEPROP 1 LASTPIN (-5375 4425) $PN 1
J 0
(-5365 4405);
DISPLAY 0.787234 (-5365 4405);
PAINT MONO (-5365 4405);
FORCEPROP 1 LASTPIN (-5375 4225) $PN 2
J 0
(-5365 4205);
DISPLAY 0.787234 (-5365 4205);
PAINT MONO (-5365 4205);
FORCEPROP 1 LAST VALUE 0.1UF
J 0
(-5325 4375);
DISPLAY 0.638298 (-5325 4375);
FORCEPROP 1 LAST TOLERANCE 10%
J 0
(-5325 4275);
DISPLAY 0.638298 (-5325 4275);
FORCEPROP 1 LAST MATERIAL X7S
J 0
(-5325 4225);
DISPLAY 0.638298 (-5325 4225);
FORCEPROP 1 LAST PACK_TYPE C0201
J 0
(-5325 4175);
DISPLAY 0.638298 (-5325 4175);
FORCEPROP 1 LAST VOLTAGE 10V
J 0
(-5325 4325);
DISPLAY 0.638298 (-5325 4325);
FORCEPROP 2 LAST CDS_LIB pure_quanta
J 0
(-5375 4325);
DISPLAY INVISIBLE (-5375 4325);
FORCEPROP 1 LAST PATH I18
J 0
(-5325 4475);
DISPLAY 0.978723 (-5325 4475);
PAINT WHITE (-5325 4475);
DISPLAY INVISIBLE (-5325 4475);
FORCEPROP 1 LAST PART_NUMBER CH4102K6E00
J 0
(-5325 4175);
DISPLAY 0.978723 (-5325 4175);
DISPLAY INVISIBLE (-5325 4175);
FORCEADD Q_CAP..1
(-5100 4325);
FORCEPROP 1 LAST LOCATION C381
J 0
(-5050 4425);
DISPLAY 0.978723 (-5050 4425);
PAINT WHITE (-5050 4425);
FORCEPROP 0 LAST $SEC 1
J 0
(-5050 4475);
DISPLAY 0.680851 (-5050 4475);
PAINT MONO (-5050 4475);
DISPLAY INVISIBLE (-5050 4475);
FORCEPROP 0 LAST CDS_SEC 1
J 0
(-5050 4475);
DISPLAY 0.680851 (-5050 4475);
DISPLAY INVISIBLE (-5050 4475);
FORCEPROP 1 LASTPIN (-5100 4425) $PN 1
J 0
(-5090 4405);
DISPLAY 0.787234 (-5090 4405);
PAINT MONO (-5090 4405);
FORCEPROP 1 LASTPIN (-5100 4225) $PN 2
J 0
(-5090 4205);
DISPLAY 0.787234 (-5090 4205);
PAINT MONO (-5090 4205);
FORCEPROP 1 LAST VALUE 0.1UF
J 0
(-5050 4375);
DISPLAY 0.638298 (-5050 4375);
FORCEPROP 1 LAST TOLERANCE 10%
J 0
(-5050 4275);
DISPLAY 0.638298 (-5050 4275);
FORCEPROP 1 LAST MATERIAL X7S
J 0
(-5050 4225);
DISPLAY 0.638298 (-5050 4225);
FORCEPROP 1 LAST PACK_TYPE C0201
J 0
(-5050 4175);
DISPLAY 0.638298 (-5050 4175);
FORCEPROP 1 LAST VOLTAGE 10V
J 0
(-5050 4325);
DISPLAY 0.638298 (-5050 4325);
FORCEPROP 2 LAST CDS_LIB pure_quanta
J 0
(-5100 4325);
DISPLAY INVISIBLE (-5100 4325);
FORCEPROP 1 LAST PATH I19
J 0
(-5050 4475);
DISPLAY 0.978723 (-5050 4475);
PAINT WHITE (-5050 4475);
DISPLAY INVISIBLE (-5050 4475);
FORCEPROP 1 LAST PART_NUMBER CH4102K6E00
J 0
(-5050 4175);
DISPLAY 0.978723 (-5050 4175);
DISPLAY INVISIBLE (-5050 4175);
FORCEADD Q_RES..1
(-7650 3900);
FORCEPROP 1 LAST LOCATION R852
J 0
(-7925 3925);
DISPLAY 0.808511 (-7925 3925);
FORCEPROP 2 LAST SEC 1
J 0
(-7700 4100);
DISPLAY 0.680851 (-7700 4100);
PAINT MONO (-7700 4100);
DISPLAY INVISIBLE (-7700 4100);
FORCEPROP 1 LASTPIN (-7750 3900) $PN 1
J 0
(-7738 3912);
DISPLAY 0.787234 (-7738 3912);
PAINT MONO (-7738 3912);
FORCEPROP 1 LASTPIN (-7550 3900) $PN 2
J 0
(-7588 3912);
DISPLAY 0.787234 (-7588 3912);
PAINT MONO (-7588 3912);
FORCEPROP 1 LAST TOLERANCE 5%
J 0
(-7600 3850);
DISPLAY 0.638298 (-7600 3850);
FORCEPROP 1 LAST PACK_TYPE 0402LF
J 0
(-7800 3850);
DISPLAY 0.638298 (-7800 3850);
FORCEPROP 1 LAST VALUE 0
J 2
(-7500 3925);
DISPLAY 0.638298 (-7500 3925);
FORCEPROP 1 LAST MATERIAL EMPTY
J 0
(-7625 3800);
DISPLAY 0.638298 (-7625 3800);
FORCEPROP 1 LAST WATTAGE 1/16W
J 2
(-7650 3800);
DISPLAY 0.638298 (-7650 3800);
FORCEPROP 2 LAST CDS_LIB pure_quanta
J 0
(-7650 3900);
DISPLAY INVISIBLE (-7650 3900);
FORCEPROP 2 LAST SEC_TYPE 0402LF
J 0
(-7700 4100);
DISPLAY 0.680851 (-7700 4100);
DISPLAY INVISIBLE (-7700 4100);
FORCEPROP 1 LAST PATH I2
J 0
(-7700 4050);
DISPLAY 0.978723 (-7700 4050);
PAINT WHITE (-7700 4050);
DISPLAY INVISIBLE (-7700 4050);
FORCEPROP 1 LAST PART_NUMBER CS00002JB13
J 0
(-7700 4000);
DISPLAY 0.978723 (-7700 4000);
DISPLAY INVISIBLE (-7700 4000);
FORCEADD Q_RES..2
R 2
(-4250 2900);
FORCEPROP 1 LAST LOCATION R858
J 2
(-4295 3025);
DISPLAY 0.978723 (-4295 3025);
FORCEPROP 0 LAST $SEC 1
J 0
(-4275 3075);
DISPLAY 0.680851 (-4275 3075);
PAINT MONO (-4275 3075);
DISPLAY INVISIBLE (-4275 3075);
FORCEPROP 0 LAST CDS_SEC 1
J 0
(-4275 3075);
DISPLAY 0.680851 (-4275 3075);
DISPLAY INVISIBLE (-4275 3075);
FORCEPROP 1 LASTPIN (-4250 3000) $PN 1
J 2
(-4255 2962);
DISPLAY 0.787234 (-4255 2962);
PAINT MONO (-4255 2962);
FORCEPROP 1 LASTPIN (-4250 2800) $PN 2
J 2
(-4255 2810);
DISPLAY 0.787234 (-4255 2810);
PAINT MONO (-4255 2810);
FORCEPROP 1 LAST TOLERANCE 5%
J 2
(-4295 2925);
DISPLAY 0.978723 (-4295 2925);
FORCEPROP 1 LAST VALUE 0
J 2
(-4295 2975);
DISPLAY 0.978723 (-4295 2975);
FORCEPROP 1 LAST WATTAGE 1/4W
J 2
(-4290 2875);
DISPLAY 0.978723 (-4290 2875);
FORCEPROP 1 LAST MATERIAL EMPTY
J 2
(-4290 2825);
DISPLAY 0.978723 (-4290 2825);
FORCEPROP 1 LAST PACK_TYPE 0603LF
J 2
(-4290 2725);
DISPLAY 0.978723 (-4290 2725);
FORCEPROP 2 LAST CDS_LIB pure_quanta
J 2
(-4250 2900);
DISPLAY INVISIBLE (-4250 2900);
FORCEPROP 1 LAST PATH I20
J 2
(-4300 3075);
DISPLAY 0.978723 (-4300 3075);
PAINT WHITE (-4300 3075);
DISPLAY INVISIBLE (-4300 3075);
FORCEPROP 1 LAST PART_NUMBER CS00006J900
J 2
(-4290 2775);
DISPLAY 0.978723 (-4290 2775);
DISPLAY INVISIBLE (-4290 2775);
FORCEADD Q_INDUCTOR..1
(-7725 4600);
FORCEPROP 1 LAST LOCATION L7
J 0
(-7850 4760);
DISPLAY 0.723404 (-7850 4760);
PAINT GREEN (-7850 4760);
FORCEPROP 0 LAST $SEC 1
J 0
(-7850 4850);
DISPLAY 0.680851 (-7850 4850);
PAINT MONO (-7850 4850);
DISPLAY INVISIBLE (-7850 4850);
FORCEPROP 0 LAST CDS_SEC 1
J 0
(-7850 4850);
DISPLAY 0.680851 (-7850 4850);
DISPLAY INVISIBLE (-7850 4850);
FORCEPROP 0 LASTPIN (-7825 4575) $PN 1
J 2
(-7835 4585);
DISPLAY 0.680851 (-7835 4585);
PAINT MONO (-7835 4585);
FORCEPROP 0 LASTPIN (-7625 4575) $PN 2
J 0
(-7615 4585);
DISPLAY 0.680851 (-7615 4585);
PAINT MONO (-7615 4585);
FORCEPROP 2 LAST PACK_TYPE SMLF
J 0
(-7850 4800);
DISPLAY 0.680851 (-7850 4800);
FORCEPROP 1 LAST MATERIAL IND
J 0
(-7850 4655);
DISPLAY 0.723404 (-7850 4655);
PAINT GREEN (-7850 4655);
FORCEPROP 2 LAST VALUE BLM21SN300SN1D/5A
J 0
(-7975 4500);
DISPLAY 0.680851 (-7975 4500);
FORCEPROP 1 LAST NEEDS_NO_SIZE TRUE
J 0
(-7725 4600);
DISPLAY 0.468085 (-7725 4600);
PAINT GREEN (-7725 4600);
DISPLAY INVISIBLE (-7725 4600);
FORCEPROP 2 LAST CDS_LIB pure_quanta
J 0
(-7725 4600);
DISPLAY INVISIBLE (-7725 4600);
FORCEPROP 1 LAST PATH I21
J 0
(-7650 4655);
DISPLAY 0.723404 (-7650 4655);
PAINT GREEN (-7650 4655);
DISPLAY INVISIBLE (-7650 4655);
FORCEPROP 1 LAST PART_NUMBER CX300SN1000
J 0
(-7850 4710);
DISPLAY 0.723404 (-7850 4710);
PAINT GREEN (-7850 4710);
DISPLAY INVISIBLE (-7850 4710);
FORCEADD P1V0..1
(-8100 5425);
FORCEPROP 3 LASTPIN (-8100 5375) SIG_NAME P1V8_CPU1_RT_1D\g
J 0
(-8090 5385);
DISPLAY 0.659574 (-8090 5385);
PAINT MONO (-8090 5385);
DISPLAY INVISIBLE (-8090 5385);
FORCEPROP 1 LAST HDL_POWER P1V8_CPU1_RT_1D
J 1
(-8100 5475);
DISPLAY 0.489362 (-8100 5475);
PAINT SKYBLUE (-8100 5475);
FORCEPROP 2 LAST CDS_LIB pure_quanta_power
J 0
(-8100 5425);
DISPLAY INVISIBLE (-8100 5425);
FORCEPROP 1 LAST PATH I22
J 0
(-8050 5450);
DISPLAY 0.872340 (-8050 5450);
PAINT AQUA (-8050 5450);
DISPLAY INVISIBLE (-8050 5450);
FORCEADD P1V0..1
(-7250 4800);
FORCEPROP 3 LASTPIN (-7250 4750) SIG_NAME P1V8_CPU1_RT2_1A\g
J 0
(-7240 4760);
DISPLAY 0.659574 (-7240 4760);
PAINT MONO (-7240 4760);
DISPLAY INVISIBLE (-7240 4760);
FORCEPROP 1 LAST HDL_POWER P1V8_CPU1_RT2_1A
J 1
(-7250 4850);
DISPLAY 0.489362 (-7250 4850);
PAINT SKYBLUE (-7250 4850);
FORCEPROP 2 LAST CDS_LIB pure_quanta_power
J 0
(-7250 4800);
DISPLAY INVISIBLE (-7250 4800);
FORCEPROP 1 LAST PATH I23
J 0
(-7200 4825);
DISPLAY 0.872340 (-7200 4825);
PAINT AQUA (-7200 4825);
DISPLAY INVISIBLE (-7200 4825);
FORCEADD Q_CAP..1
(-7000 5150);
FORCEPROP 1 LAST LOCATION C366
J 0
(-6950 5250);
DISPLAY 0.638298 (-6950 5250);
PAINT WHITE (-6950 5250);
FORCEPROP 0 LAST $SEC 1
J 0
(-6950 5300);
DISPLAY 0.680851 (-6950 5300);
PAINT MONO (-6950 5300);
DISPLAY INVISIBLE (-6950 5300);
FORCEPROP 0 LAST CDS_SEC 1
J 0
(-6950 5300);
DISPLAY 0.680851 (-6950 5300);
DISPLAY INVISIBLE (-6950 5300);
FORCEPROP 1 LASTPIN (-7000 5250) $PN 1
J 0
(-6990 5230);
DISPLAY 0.787234 (-6990 5230);
PAINT MONO (-6990 5230);
FORCEPROP 1 LASTPIN (-7000 5050) $PN 2
J 0
(-6990 5030);
DISPLAY 0.787234 (-6990 5030);
PAINT MONO (-6990 5030);
FORCEPROP 1 LAST MATERIAL X6S
J 0
(-6950 5050);
DISPLAY 0.510638 (-6950 5050);
FORCEPROP 1 LAST PACK_TYPE C0805
J 0
(-6950 5000);
DISPLAY 0.510638 (-6950 5000);
FORCEPROP 1 LAST VOLTAGE 4V
J 0
(-6950 5150);
DISPLAY 0.510638 (-6950 5150);
FORCEPROP 1 LAST VALUE 100UF
J 0
(-6950 5200);
DISPLAY 0.510638 (-6950 5200);
FORCEPROP 1 LAST TOLERANCE 20%
J 0
(-6950 5100);
DISPLAY 0.510638 (-6950 5100);
FORCEPROP 2 LAST CDS_LIB pure_quanta
J 0
(-7000 5150);
DISPLAY INVISIBLE (-7000 5150);
FORCEPROP 1 LAST PATH I24
J 0
(-6950 5300);
DISPLAY 0.978723 (-6950 5300);
PAINT WHITE (-6950 5300);
DISPLAY INVISIBLE (-6950 5300);
FORCEPROP 1 LAST PART_NUMBER CH710KMEA01
J 0
(-6950 5000);
DISPLAY 0.404255 (-6950 5000);
DISPLAY INVISIBLE (-6950 5000);
FORCEADD Q_CAP..1
(-6750 5150);
FORCEPROP 1 LAST LOCATION C368
J 0
(-6700 5250);
DISPLAY 0.510638 (-6700 5250);
PAINT WHITE (-6700 5250);
FORCEPROP 0 LAST $SEC 1
J 0
(-6700 5275);
DISPLAY 0.680851 (-6700 5275);
PAINT MONO (-6700 5275);
DISPLAY INVISIBLE (-6700 5275);
FORCEPROP 0 LAST CDS_SEC 1
J 0
(-6700 5275);
DISPLAY 0.680851 (-6700 5275);
DISPLAY INVISIBLE (-6700 5275);
FORCEPROP 1 LASTPIN (-6750 5250) $PN 1
J 0
(-6740 5230);
DISPLAY 0.787234 (-6740 5230);
PAINT MONO (-6740 5230);
FORCEPROP 1 LASTPIN (-6750 5050) $PN 2
J 0
(-6740 5030);
DISPLAY 0.787234 (-6740 5030);
PAINT MONO (-6740 5030);
FORCEPROP 1 LAST PACK_TYPE C0402
J 0
(-6700 5000);
DISPLAY 0.510638 (-6700 5000);
FORCEPROP 1 LAST VOLTAGE 4V
J 0
(-6700 5150);
DISPLAY 0.510638 (-6700 5150);
FORCEPROP 1 LAST MATERIAL X6S
J 0
(-6700 5050);
DISPLAY 0.510638 (-6700 5050);
FORCEPROP 1 LAST TOLERANCE 20%
J 0
(-6700 5100);
DISPLAY 0.510638 (-6700 5100);
FORCEPROP 1 LAST VALUE 22UF
J 0
(-6700 5200);
DISPLAY 0.510638 (-6700 5200);
FORCEPROP 2 LAST CDS_LIB pure_quanta
J 0
(-6750 5150);
DISPLAY INVISIBLE (-6750 5150);
FORCEPROP 1 LAST PATH I25
J 0
(-6700 5300);
DISPLAY 0.978723 (-6700 5300);
PAINT WHITE (-6700 5300);
DISPLAY INVISIBLE (-6700 5300);
FORCEPROP 1 LAST PART_NUMBER CH622KMEB02
J 0
(-6700 5000);
DISPLAY 0.978723 (-6700 5000);
DISPLAY INVISIBLE (-6700 5000);
FORCEADD UNIVERSAL_GND..1
(-6325 4850);
FORCEPROP 3 LASTPIN (-6325 4900) SIG_NAME GND\g
J 0
(-6315 4910);
DISPLAY 0.659574 (-6315 4910);
PAINT MONO (-6315 4910);
DISPLAY INVISIBLE (-6315 4910);
FORCEPROP 2 LAST CDS_LIB pure_quanta_power
J 0
(-6325 4850);
DISPLAY INVISIBLE (-6325 4850);
FORCEPROP 1 LAST HDL_POWER GND
J 1
(-6300 4775);
DISPLAY 0.872340 (-6300 4775);
PAINT GREEN (-6300 4775);
DISPLAY INVISIBLE (-6300 4775);
FORCEPROP 1 LAST PATH I26
J 0
(-6250 4850);
DISPLAY 0.872340 (-6250 4850);
PAINT AQUA (-6250 4850);
DISPLAY INVISIBLE (-6250 4850);
FORCEADD Q_CAP..1
(-6500 5125);
FORCEPROP 1 LAST LOCATION C370
J 0
(-6450 5225);
DISPLAY 0.638298 (-6450 5225);
PAINT WHITE (-6450 5225);
FORCEPROP 0 LAST $SEC 1
J 0
(-6450 5275);
DISPLAY 0.680851 (-6450 5275);
PAINT MONO (-6450 5275);
DISPLAY INVISIBLE (-6450 5275);
FORCEPROP 0 LAST CDS_SEC 1
J 0
(-6450 5275);
DISPLAY 0.680851 (-6450 5275);
DISPLAY INVISIBLE (-6450 5275);
FORCEPROP 1 LASTPIN (-6500 5225) $PN 1
J 0
(-6490 5205);
DISPLAY 0.787234 (-6490 5205);
PAINT MONO (-6490 5205);
FORCEPROP 1 LASTPIN (-6500 5025) $PN 2
J 0
(-6490 5005);
DISPLAY 0.787234 (-6490 5005);
PAINT MONO (-6490 5005);
FORCEPROP 1 LAST VALUE 10UF
J 0
(-6450 5175);
DISPLAY 0.510638 (-6450 5175);
FORCEPROP 1 LAST MATERIAL X6S
J 0
(-6450 5025);
DISPLAY 0.510638 (-6450 5025);
FORCEPROP 1 LAST PACK_TYPE C0402
J 0
(-6450 4975);
DISPLAY 0.510638 (-6450 4975);
FORCEPROP 1 LAST TOLERANCE 20%
J 0
(-6450 5075);
DISPLAY 0.510638 (-6450 5075);
FORCEPROP 1 LAST VOLTAGE 6.3V
J 0
(-6450 5125);
DISPLAY 0.510638 (-6450 5125);
FORCEPROP 2 LAST CDS_LIB pure_quanta
J 0
(-6500 5125);
DISPLAY INVISIBLE (-6500 5125);
FORCEPROP 1 LAST PATH I27
J 0
(-6450 5275);
DISPLAY 0.978723 (-6450 5275);
PAINT WHITE (-6450 5275);
DISPLAY INVISIBLE (-6450 5275);
FORCEPROP 1 LAST PART_NUMBER CH6101MEB01
J 0
(-6450 4975);
DISPLAY 0.978723 (-6450 4975);
DISPLAY INVISIBLE (-6450 4975);
FORCEADD Q_CAP..1
(-6250 5125);
FORCEPROP 1 LAST LOCATION C373
J 0
(-6200 5225);
DISPLAY 0.638298 (-6200 5225);
PAINT WHITE (-6200 5225);
FORCEPROP 0 LAST $SEC 1
J 0
(-6200 5275);
DISPLAY 0.680851 (-6200 5275);
PAINT MONO (-6200 5275);
DISPLAY INVISIBLE (-6200 5275);
FORCEPROP 0 LAST CDS_SEC 1
J 0
(-6200 5275);
DISPLAY 0.680851 (-6200 5275);
DISPLAY INVISIBLE (-6200 5275);
FORCEPROP 1 LASTPIN (-6250 5225) $PN 1
J 0
(-6240 5205);
DISPLAY 0.787234 (-6240 5205);
PAINT MONO (-6240 5205);
FORCEPROP 1 LASTPIN (-6250 5025) $PN 2
J 0
(-6240 5005);
DISPLAY 0.787234 (-6240 5005);
PAINT MONO (-6240 5005);
FORCEPROP 1 LAST VOLTAGE 6.3V
J 0
(-6200 5125);
DISPLAY 0.510638 (-6200 5125);
FORCEPROP 1 LAST MATERIAL X6S
J 0
(-6200 5025);
DISPLAY 0.510638 (-6200 5025);
FORCEPROP 1 LAST PACK_TYPE 0402
J 0
(-6200 4975);
DISPLAY 0.510638 (-6200 4975);
FORCEPROP 1 LAST TOLERANCE 20%
J 0
(-6200 5075);
DISPLAY 0.510638 (-6200 5075);
FORCEPROP 1 LAST VALUE 4.7UF
J 0
(-6200 5175);
DISPLAY 0.510638 (-6200 5175);
FORCEPROP 2 LAST CDS_LIB pure_quanta
J 0
(-6250 5125);
DISPLAY INVISIBLE (-6250 5125);
FORCEPROP 1 LAST PATH I28
J 0
(-6200 5275);
DISPLAY 0.978723 (-6200 5275);
PAINT WHITE (-6200 5275);
DISPLAY INVISIBLE (-6200 5275);
FORCEPROP 1 LAST PART_NUMBER CH5471MEB01
J 0
(-6200 4975);
DISPLAY 0.978723 (-6200 4975);
DISPLAY INVISIBLE (-6200 4975);
FORCEADD VCC_CORE..1
(-4250 6100);
FORCEPROP 3 LASTPIN (-4250 6050) SIG_NAME P0V9_CPU1_RT_2D\g
J 0
(-4240 6060);
DISPLAY 0.659574 (-4240 6060);
PAINT MONO (-4240 6060);
DISPLAY INVISIBLE (-4240 6060);
FORCEPROP 1 LAST HDL_POWER P0V9_CPU1_RT_2D
J 1
(-4250 6150);
DISPLAY 0.617021 (-4250 6150);
PAINT GREEN (-4250 6150);
FORCEPROP 2 LAST CDS_LIB pure_quanta_power
J 0
(-4250 6100);
DISPLAY INVISIBLE (-4250 6100);
FORCEPROP 1 LAST PATH I29
J 0
(-4200 6125);
DISPLAY 0.872340 (-4200 6125);
PAINT AQUA (-4200 6125);
DISPLAY INVISIBLE (-4200 6125);
FORCEADD Q_RES..1
(-7650 3700);
FORCEPROP 1 LAST LOCATION R853
J 0
(-7925 3700);
DISPLAY 0.787234 (-7925 3700);
FORCEPROP 2 LAST SEC 1
J 0
(-7700 3900);
DISPLAY 0.680851 (-7700 3900);
PAINT MONO (-7700 3900);
DISPLAY INVISIBLE (-7700 3900);
FORCEPROP 1 LASTPIN (-7750 3700) $PN 1
J 0
(-7738 3712);
DISPLAY 0.787234 (-7738 3712);
PAINT MONO (-7738 3712);
FORCEPROP 1 LASTPIN (-7550 3700) $PN 2
J 0
(-7588 3712);
DISPLAY 0.787234 (-7588 3712);
PAINT MONO (-7588 3712);
FORCEPROP 1 LAST PACK_TYPE 0402LF
J 0
(-7800 3650);
DISPLAY 0.638298 (-7800 3650);
FORCEPROP 1 LAST TOLERANCE 5%
J 0
(-7600 3650);
DISPLAY 0.638298 (-7600 3650);
FORCEPROP 1 LAST WATTAGE 1/16W
J 2
(-7650 3600);
DISPLAY 0.638298 (-7650 3600);
FORCEPROP 1 LAST MATERIAL EMPTY
J 0
(-7625 3600);
DISPLAY 0.638298 (-7625 3600);
FORCEPROP 1 LAST VALUE 0
J 2
(-7500 3725);
DISPLAY 0.638298 (-7500 3725);
FORCEPROP 2 LAST SEC_TYPE 0402LF
J 0
(-7700 3900);
DISPLAY 0.680851 (-7700 3900);
DISPLAY INVISIBLE (-7700 3900);
FORCEPROP 2 LAST CDS_LIB pure_quanta
J 0
(-7650 3700);
DISPLAY INVISIBLE (-7650 3700);
FORCEPROP 1 LAST PATH I3
J 0
(-7700 3850);
DISPLAY 0.978723 (-7700 3850);
PAINT WHITE (-7700 3850);
DISPLAY INVISIBLE (-7700 3850);
FORCEPROP 1 LAST PART_NUMBER CS00002JB13
J 0
(-7700 3800);
DISPLAY 0.978723 (-7700 3800);
DISPLAY INVISIBLE (-7700 3800);
FORCEADD VCC_CORE..1
(-3100 1800);
FORCEPROP 3 LASTPIN (-3100 1750) SIG_NAME P0V9_CPU1_RT2_2A_2D\g
J 0
(-3090 1760);
DISPLAY 0.659574 (-3090 1760);
PAINT MONO (-3090 1760);
DISPLAY INVISIBLE (-3090 1760);
FORCEPROP 1 LAST HDL_POWER P0V9_CPU1_RT2_2A_2D
J 1
(-3100 1850);
DISPLAY 0.617021 (-3100 1850);
PAINT GREEN (-3100 1850);
FORCEPROP 2 LAST CDS_LIB pure_quanta_power
J 0
(-3100 1800);
DISPLAY INVISIBLE (-3100 1800);
FORCEPROP 1 LAST PATH I30
J 0
(-3050 1825);
DISPLAY 0.872340 (-3050 1825);
PAINT AQUA (-3050 1825);
DISPLAY INVISIBLE (-3050 1825);
FORCEADD Q_CAP..1
(-3150 2375);
FORCEPROP 1 LAST LOCATION C421
J 0
(-3100 2475);
DISPLAY 0.978723 (-3100 2475);
PAINT WHITE (-3100 2475);
FORCEPROP 0 LAST $SEC 1
J 0
(-3100 2525);
DISPLAY 0.680851 (-3100 2525);
PAINT MONO (-3100 2525);
DISPLAY INVISIBLE (-3100 2525);
FORCEPROP 0 LAST CDS_SEC 1
J 0
(-3100 2525);
DISPLAY 0.680851 (-3100 2525);
DISPLAY INVISIBLE (-3100 2525);
FORCEPROP 1 LASTPIN (-3150 2475) $PN 1
J 0
(-3140 2455);
DISPLAY 0.787234 (-3140 2455);
PAINT MONO (-3140 2455);
FORCEPROP 1 LASTPIN (-3150 2275) $PN 2
J 0
(-3140 2255);
DISPLAY 0.787234 (-3140 2255);
PAINT MONO (-3140 2255);
FORCEPROP 1 LAST VALUE 0.1UF
J 0
(-3100 2425);
DISPLAY 0.638298 (-3100 2425);
FORCEPROP 1 LAST VOLTAGE 10V
J 0
(-3100 2375);
DISPLAY 0.638298 (-3100 2375);
FORCEPROP 1 LAST TOLERANCE 10%
J 0
(-3100 2325);
DISPLAY 0.638298 (-3100 2325);
FORCEPROP 1 LAST MATERIAL X7S
J 0
(-3100 2275);
DISPLAY 0.638298 (-3100 2275);
FORCEPROP 1 LAST PACK_TYPE C0201
J 0
(-3100 2225);
DISPLAY 0.638298 (-3100 2225);
FORCEPROP 2 LAST CDS_LIB pure_quanta
J 0
(-3150 2375);
DISPLAY INVISIBLE (-3150 2375);
FORCEPROP 1 LAST PATH I31
J 0
(-3100 2525);
DISPLAY 0.978723 (-3100 2525);
PAINT WHITE (-3100 2525);
DISPLAY INVISIBLE (-3100 2525);
FORCEPROP 1 LAST PART_NUMBER CH4102K6E00
J 0
(-3100 2225);
DISPLAY 0.978723 (-3100 2225);
DISPLAY INVISIBLE (-3100 2225);
FORCEADD UNIVERSAL_GND..1
(-2275 950);
FORCEPROP 3 LASTPIN (-2275 1000) SIG_NAME GND\g
J 0
(-2265 1010);
DISPLAY 0.659574 (-2265 1010);
PAINT MONO (-2265 1010);
DISPLAY INVISIBLE (-2265 1010);
FORCEPROP 2 LAST CDS_LIB pure_quanta_power
J 0
(-2275 950);
DISPLAY INVISIBLE (-2275 950);
FORCEPROP 1 LAST HDL_POWER GND
J 1
(-2250 875);
DISPLAY 0.872340 (-2250 875);
PAINT GREEN (-2250 875);
DISPLAY INVISIBLE (-2250 875);
FORCEPROP 1 LAST PATH I34
J 0
(-2200 950);
DISPLAY 0.872340 (-2200 950);
PAINT AQUA (-2200 950);
DISPLAY INVISIBLE (-2200 950);
FORCEADD Q_CAP..1
(-2425 1275);
FORCEPROP 1 LAST LOCATION C396
J 0
(-2375 1375);
DISPLAY 0.978723 (-2375 1375);
PAINT WHITE (-2375 1375);
FORCEPROP 0 LAST $SEC 1
J 0
(-2375 1425);
DISPLAY 0.680851 (-2375 1425);
PAINT MONO (-2375 1425);
DISPLAY INVISIBLE (-2375 1425);
FORCEPROP 0 LAST CDS_SEC 1
J 0
(-2375 1425);
DISPLAY 0.680851 (-2375 1425);
DISPLAY INVISIBLE (-2375 1425);
FORCEPROP 1 LASTPIN (-2425 1375) $PN 1
J 0
(-2415 1355);
DISPLAY 0.787234 (-2415 1355);
PAINT MONO (-2415 1355);
FORCEPROP 1 LASTPIN (-2425 1175) $PN 2
J 0
(-2415 1155);
DISPLAY 0.787234 (-2415 1155);
PAINT MONO (-2415 1155);
FORCEPROP 1 LAST TOLERANCE 10%
J 0
(-2375 1225);
DISPLAY 0.638298 (-2375 1225);
FORCEPROP 1 LAST VOLTAGE 10V
J 0
(-2375 1275);
DISPLAY 0.638298 (-2375 1275);
FORCEPROP 1 LAST MATERIAL X7S
J 0
(-2375 1175);
DISPLAY 0.638298 (-2375 1175);
FORCEPROP 1 LAST PACK_TYPE C0201
J 0
(-2375 1125);
DISPLAY 0.638298 (-2375 1125);
FORCEPROP 1 LAST VALUE 0.1UF
J 0
(-2375 1325);
DISPLAY 0.638298 (-2375 1325);
FORCEPROP 2 LAST CDS_LIB pure_quanta
J 0
(-2425 1275);
DISPLAY INVISIBLE (-2425 1275);
FORCEPROP 1 LAST PATH I35
J 0
(-2375 1425);
DISPLAY 0.978723 (-2375 1425);
PAINT WHITE (-2375 1425);
DISPLAY INVISIBLE (-2375 1425);
FORCEPROP 1 LAST PART_NUMBER CH4102K6E00
J 0
(-2375 1125);
DISPLAY 0.978723 (-2375 1125);
DISPLAY INVISIBLE (-2375 1125);
FORCEADD Q_CAP..1
(-2175 1275);
FORCEPROP 1 LAST LOCATION C397
J 0
(-2125 1375);
DISPLAY 0.978723 (-2125 1375);
PAINT WHITE (-2125 1375);
FORCEPROP 0 LAST $SEC 1
J 0
(-2125 1425);
DISPLAY 0.680851 (-2125 1425);
PAINT MONO (-2125 1425);
DISPLAY INVISIBLE (-2125 1425);
FORCEPROP 0 LAST CDS_SEC 1
J 0
(-2125 1425);
DISPLAY 0.680851 (-2125 1425);
DISPLAY INVISIBLE (-2125 1425);
FORCEPROP 1 LASTPIN (-2175 1375) $PN 1
J 0
(-2165 1355);
DISPLAY 0.787234 (-2165 1355);
PAINT MONO (-2165 1355);
FORCEPROP 1 LASTPIN (-2175 1175) $PN 2
J 0
(-2165 1155);
DISPLAY 0.787234 (-2165 1155);
PAINT MONO (-2165 1155);
FORCEPROP 1 LAST TOLERANCE 10%
J 0
(-2125 1225);
DISPLAY 0.638298 (-2125 1225);
FORCEPROP 1 LAST VOLTAGE 10V
J 0
(-2125 1275);
DISPLAY 0.638298 (-2125 1275);
FORCEPROP 1 LAST MATERIAL X7S
J 0
(-2125 1175);
DISPLAY 0.638298 (-2125 1175);
FORCEPROP 1 LAST VALUE 0.1UF
J 0
(-2125 1325);
DISPLAY 0.638298 (-2125 1325);
FORCEPROP 1 LAST PACK_TYPE C0201
J 0
(-2125 1125);
DISPLAY 0.638298 (-2125 1125);
FORCEPROP 2 LAST CDS_LIB pure_quanta
J 0
(-2175 1275);
DISPLAY INVISIBLE (-2175 1275);
FORCEPROP 1 LAST PATH I36
J 0
(-2125 1425);
DISPLAY 0.978723 (-2125 1425);
PAINT WHITE (-2125 1425);
DISPLAY INVISIBLE (-2125 1425);
FORCEPROP 1 LAST PART_NUMBER CH4102K6E00
J 0
(-2125 1125);
DISPLAY 0.978723 (-2125 1125);
DISPLAY INVISIBLE (-2125 1125);
FORCEADD Q_CAP..1
(-2850 2375);
FORCEPROP 1 LAST LOCATION C427
J 0
(-2800 2475);
DISPLAY 0.978723 (-2800 2475);
PAINT WHITE (-2800 2475);
FORCEPROP 0 LAST $SEC 1
J 0
(-2800 2525);
DISPLAY 0.680851 (-2800 2525);
PAINT MONO (-2800 2525);
DISPLAY INVISIBLE (-2800 2525);
FORCEPROP 0 LAST CDS_SEC 1
J 0
(-2800 2525);
DISPLAY 0.680851 (-2800 2525);
DISPLAY INVISIBLE (-2800 2525);
FORCEPROP 1 LASTPIN (-2850 2475) $PN 1
J 0
(-2840 2455);
DISPLAY 0.787234 (-2840 2455);
PAINT MONO (-2840 2455);
FORCEPROP 1 LASTPIN (-2850 2275) $PN 2
J 0
(-2840 2255);
DISPLAY 0.787234 (-2840 2255);
PAINT MONO (-2840 2255);
FORCEPROP 1 LAST VALUE 0.1UF
J 0
(-2800 2425);
DISPLAY 0.638298 (-2800 2425);
FORCEPROP 1 LAST PACK_TYPE C0201
J 0
(-2800 2225);
DISPLAY 0.638298 (-2800 2225);
FORCEPROP 1 LAST MATERIAL X7S
J 0
(-2800 2275);
DISPLAY 0.638298 (-2800 2275);
FORCEPROP 1 LAST TOLERANCE 10%
J 0
(-2800 2325);
DISPLAY 0.638298 (-2800 2325);
FORCEPROP 1 LAST VOLTAGE 10V
J 0
(-2800 2375);
DISPLAY 0.638298 (-2800 2375);
FORCEPROP 2 LAST CDS_LIB pure_quanta
J 0
(-2850 2375);
DISPLAY INVISIBLE (-2850 2375);
FORCEPROP 1 LAST PATH I37
J 0
(-2800 2525);
DISPLAY 0.978723 (-2800 2525);
PAINT WHITE (-2800 2525);
DISPLAY INVISIBLE (-2800 2525);
FORCEPROP 1 LAST PART_NUMBER CH4102K6E00
J 0
(-2800 2225);
DISPLAY 0.978723 (-2800 2225);
DISPLAY INVISIBLE (-2800 2225);
FORCEADD Q_CAP..1
(-2625 2375);
FORCEPROP 1 LAST LOCATION C393
J 0
(-2575 2475);
DISPLAY 0.978723 (-2575 2475);
PAINT WHITE (-2575 2475);
FORCEPROP 0 LAST $SEC 1
J 0
(-2575 2525);
DISPLAY 0.680851 (-2575 2525);
PAINT MONO (-2575 2525);
DISPLAY INVISIBLE (-2575 2525);
FORCEPROP 0 LAST CDS_SEC 1
J 0
(-2575 2525);
DISPLAY 0.680851 (-2575 2525);
DISPLAY INVISIBLE (-2575 2525);
FORCEPROP 1 LASTPIN (-2625 2475) $PN 1
J 0
(-2615 2455);
DISPLAY 0.787234 (-2615 2455);
PAINT MONO (-2615 2455);
FORCEPROP 1 LASTPIN (-2625 2275) $PN 2
J 0
(-2615 2255);
DISPLAY 0.787234 (-2615 2255);
PAINT MONO (-2615 2255);
FORCEPROP 1 LAST VALUE 0.1UF
J 0
(-2575 2425);
DISPLAY 0.638298 (-2575 2425);
FORCEPROP 1 LAST VOLTAGE 10V
J 0
(-2575 2375);
DISPLAY 0.638298 (-2575 2375);
FORCEPROP 1 LAST TOLERANCE 10%
J 0
(-2575 2325);
DISPLAY 0.638298 (-2575 2325);
FORCEPROP 1 LAST MATERIAL X7S
J 0
(-2575 2275);
DISPLAY 0.638298 (-2575 2275);
FORCEPROP 1 LAST PACK_TYPE C0201
J 0
(-2575 2225);
DISPLAY 0.638298 (-2575 2225);
FORCEPROP 2 LAST CDS_LIB pure_quanta
J 0
(-2625 2375);
DISPLAY INVISIBLE (-2625 2375);
FORCEPROP 1 LAST PATH I38
J 0
(-2575 2525);
DISPLAY 0.978723 (-2575 2525);
PAINT WHITE (-2575 2525);
DISPLAY INVISIBLE (-2575 2525);
FORCEPROP 1 LAST PART_NUMBER CH4102K6E00
J 0
(-2575 2225);
DISPLAY 0.978723 (-2575 2225);
DISPLAY INVISIBLE (-2575 2225);
FORCEADD Q_CAP..1
(-2375 2375);
FORCEPROP 1 LAST LOCATION C430
J 0
(-2325 2475);
DISPLAY 0.978723 (-2325 2475);
PAINT WHITE (-2325 2475);
FORCEPROP 0 LAST $SEC 1
J 0
(-2325 2525);
DISPLAY 0.680851 (-2325 2525);
PAINT MONO (-2325 2525);
DISPLAY INVISIBLE (-2325 2525);
FORCEPROP 0 LAST CDS_SEC 1
J 0
(-2325 2525);
DISPLAY 0.680851 (-2325 2525);
DISPLAY INVISIBLE (-2325 2525);
FORCEPROP 1 LASTPIN (-2375 2475) $PN 1
J 0
(-2365 2455);
DISPLAY 0.787234 (-2365 2455);
PAINT MONO (-2365 2455);
FORCEPROP 1 LASTPIN (-2375 2275) $PN 2
J 0
(-2365 2255);
DISPLAY 0.787234 (-2365 2255);
PAINT MONO (-2365 2255);
FORCEPROP 1 LAST VOLTAGE 10V
J 0
(-2325 2375);
DISPLAY 0.638298 (-2325 2375);
FORCEPROP 1 LAST MATERIAL X7S
J 0
(-2325 2275);
DISPLAY 0.638298 (-2325 2275);
FORCEPROP 1 LAST PACK_TYPE C0201
J 0
(-2325 2225);
DISPLAY 0.638298 (-2325 2225);
FORCEPROP 1 LAST TOLERANCE 10%
J 0
(-2325 2325);
DISPLAY 0.638298 (-2325 2325);
FORCEPROP 1 LAST VALUE 0.1UF
J 0
(-2325 2425);
DISPLAY 0.638298 (-2325 2425);
FORCEPROP 2 LAST CDS_LIB pure_quanta
J 0
(-2375 2375);
DISPLAY INVISIBLE (-2375 2375);
FORCEPROP 1 LAST PATH I39
J 0
(-2325 2525);
DISPLAY 0.978723 (-2325 2525);
PAINT WHITE (-2325 2525);
DISPLAY INVISIBLE (-2325 2525);
FORCEPROP 1 LAST PART_NUMBER CH4102K6E00
J 0
(-2325 2225);
DISPLAY 0.978723 (-2325 2225);
DISPLAY INVISIBLE (-2325 2225);
FORCEADD Q_CAP..1
(-2125 2375);
FORCEPROP 1 LAST LOCATION C400
J 0
(-2075 2475);
DISPLAY 0.978723 (-2075 2475);
PAINT WHITE (-2075 2475);
FORCEPROP 0 LAST $SEC 1
J 0
(-2075 2525);
DISPLAY 0.680851 (-2075 2525);
PAINT MONO (-2075 2525);
DISPLAY INVISIBLE (-2075 2525);
FORCEPROP 0 LAST CDS_SEC 1
J 0
(-2075 2525);
DISPLAY 0.680851 (-2075 2525);
DISPLAY INVISIBLE (-2075 2525);
FORCEPROP 1 LASTPIN (-2125 2475) $PN 1
J 0
(-2115 2455);
DISPLAY 0.787234 (-2115 2455);
PAINT MONO (-2115 2455);
FORCEPROP 1 LASTPIN (-2125 2275) $PN 2
J 0
(-2115 2255);
DISPLAY 0.787234 (-2115 2255);
PAINT MONO (-2115 2255);
FORCEPROP 1 LAST PACK_TYPE C0201
J 0
(-2075 2225);
DISPLAY 0.638298 (-2075 2225);
FORCEPROP 1 LAST VOLTAGE 10V
J 0
(-2075 2375);
DISPLAY 0.638298 (-2075 2375);
FORCEPROP 1 LAST TOLERANCE 10%
J 0
(-2075 2325);
DISPLAY 0.638298 (-2075 2325);
FORCEPROP 1 LAST MATERIAL X7S
J 0
(-2075 2275);
DISPLAY 0.638298 (-2075 2275);
FORCEPROP 1 LAST VALUE 0.1UF
J 0
(-2075 2425);
DISPLAY 0.638298 (-2075 2425);
FORCEPROP 2 LAST CDS_LIB pure_quanta
J 0
(-2125 2375);
DISPLAY INVISIBLE (-2125 2375);
FORCEPROP 1 LAST PATH I40
J 0
(-2075 2525);
DISPLAY 0.978723 (-2075 2525);
PAINT WHITE (-2075 2525);
DISPLAY INVISIBLE (-2075 2525);
FORCEPROP 1 LAST PART_NUMBER CH4102K6E00
J 0
(-2075 2225);
DISPLAY 0.978723 (-2075 2225);
DISPLAY INVISIBLE (-2075 2225);
FORCEADD Q_RES..1
(-3875 2625);
FORCEPROP 1 LAST LOCATION R859
J 0
(-3925 2675);
DISPLAY 0.978723 (-3925 2675);
FORCEPROP 0 LAST $SEC 1
J 0
(-3925 2725);
DISPLAY 0.680851 (-3925 2725);
PAINT MONO (-3925 2725);
DISPLAY INVISIBLE (-3925 2725);
FORCEPROP 0 LAST CDS_SEC 1
J 0
(-3925 2725);
DISPLAY 0.680851 (-3925 2725);
DISPLAY INVISIBLE (-3925 2725);
FORCEPROP 1 LASTPIN (-3975 2625) $PN 1
J 0
(-3963 2637);
DISPLAY 0.787234 (-3963 2637);
PAINT MONO (-3963 2637);
FORCEPROP 1 LASTPIN (-3775 2625) $PN 2
J 0
(-3813 2637);
DISPLAY 0.787234 (-3813 2637);
PAINT MONO (-3813 2637);
FORCEPROP 1 LAST MATERIAL CHIP
J 0
(-3875 2475);
DISPLAY 0.978723 (-3875 2475);
FORCEPROP 1 LAST PACK_TYPE 0603LF
J 0
(-3625 2475);
DISPLAY 0.978723 (-3625 2475);
FORCEPROP 1 LAST TOLERANCE 5%
J 0
(-3875 2525);
DISPLAY 0.978723 (-3875 2525);
FORCEPROP 1 LAST WATTAGE 1/4W
J 2
(-3900 2475);
DISPLAY 0.978723 (-3900 2475);
FORCEPROP 1 LAST VALUE 0
J 2
(-3900 2525);
DISPLAY 0.978723 (-3900 2525);
FORCEPROP 2 LAST CDS_LIB pure_quanta
J 0
(-3875 2625);
DISPLAY INVISIBLE (-3875 2625);
FORCEPROP 1 LAST PATH I41
J 0
(-3925 2775);
DISPLAY 0.978723 (-3925 2775);
PAINT WHITE (-3925 2775);
DISPLAY INVISIBLE (-3925 2775);
FORCEPROP 1 LAST PART_NUMBER CS00006J900
J 0
(-4100 2400);
DISPLAY 0.978723 (-4100 2400);
DISPLAY INVISIBLE (-4100 2400);
FORCEADD Q_CAP..1
(-3425 3075);
FORCEPROP 1 LAST LOCATION C384
J 0
(-3375 3175);
DISPLAY 0.978723 (-3375 3175);
PAINT WHITE (-3375 3175);
FORCEPROP 0 LAST $SEC 1
J 0
(-3375 3225);
DISPLAY 0.680851 (-3375 3225);
PAINT MONO (-3375 3225);
DISPLAY INVISIBLE (-3375 3225);
FORCEPROP 0 LAST CDS_SEC 1
J 0
(-3375 3225);
DISPLAY 0.680851 (-3375 3225);
DISPLAY INVISIBLE (-3375 3225);
FORCEPROP 1 LASTPIN (-3425 3175) $PN 1
J 0
(-3415 3155);
DISPLAY 0.787234 (-3415 3155);
PAINT MONO (-3415 3155);
FORCEPROP 1 LASTPIN (-3425 2975) $PN 2
J 0
(-3415 2955);
DISPLAY 0.787234 (-3415 2955);
PAINT MONO (-3415 2955);
FORCEPROP 1 LAST MATERIAL X6S
J 0
(-3375 2975);
DISPLAY 0.510638 (-3375 2975);
FORCEPROP 1 LAST PACK_TYPE 0201
J 0
(-3375 2925);
DISPLAY 0.510638 (-3375 2925);
FORCEPROP 1 LAST TOLERANCE 20%
J 0
(-3375 3025);
DISPLAY 0.510638 (-3375 3025);
FORCEPROP 1 LAST VOLTAGE 4V
J 0
(-3375 3075);
DISPLAY 0.510638 (-3375 3075);
FORCEPROP 1 LAST VALUE 1UF
J 0
(-3375 3125);
DISPLAY 0.510638 (-3375 3125);
FORCEPROP 2 LAST CDS_LIB pure_quanta
J 0
(-3425 3075);
DISPLAY INVISIBLE (-3425 3075);
FORCEPROP 1 LAST PATH I42
J 0
(-3375 3225);
DISPLAY 0.978723 (-3375 3225);
PAINT WHITE (-3375 3225);
DISPLAY INVISIBLE (-3375 3225);
FORCEPROP 1 LAST PART_NUMBER CH-10KMEE00
J 0
(-3375 2925);
DISPLAY 0.510638 (-3375 2925);
DISPLAY INVISIBLE (-3375 2925);
FORCEADD Q_CAP..1
(-3200 3075);
FORCEPROP 1 LAST LOCATION C387
J 0
(-3150 3175);
DISPLAY 0.978723 (-3150 3175);
PAINT WHITE (-3150 3175);
FORCEPROP 0 LAST $SEC 1
J 0
(-3150 3225);
DISPLAY 0.680851 (-3150 3225);
PAINT MONO (-3150 3225);
DISPLAY INVISIBLE (-3150 3225);
FORCEPROP 0 LAST CDS_SEC 1
J 0
(-3150 3225);
DISPLAY 0.680851 (-3150 3225);
DISPLAY INVISIBLE (-3150 3225);
FORCEPROP 1 LASTPIN (-3200 3175) $PN 1
J 0
(-3190 3155);
DISPLAY 0.787234 (-3190 3155);
PAINT MONO (-3190 3155);
FORCEPROP 1 LASTPIN (-3200 2975) $PN 2
J 0
(-3190 2955);
DISPLAY 0.787234 (-3190 2955);
PAINT MONO (-3190 2955);
FORCEPROP 1 LAST VOLTAGE 4V
J 0
(-3150 3075);
DISPLAY 0.510638 (-3150 3075);
FORCEPROP 1 LAST TOLERANCE 20%
J 0
(-3150 3025);
DISPLAY 0.510638 (-3150 3025);
FORCEPROP 1 LAST MATERIAL X6S
J 0
(-3150 2975);
DISPLAY 0.510638 (-3150 2975);
FORCEPROP 1 LAST VALUE 1UF
J 0
(-3150 3125);
DISPLAY 0.510638 (-3150 3125);
FORCEPROP 1 LAST PACK_TYPE 0201
J 0
(-3150 2925);
DISPLAY 0.510638 (-3150 2925);
FORCEPROP 2 LAST CDS_LIB pure_quanta
J 0
(-3200 3075);
DISPLAY INVISIBLE (-3200 3075);
FORCEPROP 1 LAST PATH I43
J 0
(-3150 3225);
DISPLAY 0.978723 (-3150 3225);
PAINT WHITE (-3150 3225);
DISPLAY INVISIBLE (-3150 3225);
FORCEPROP 1 LAST PART_NUMBER CH-10KMEE00
J 0
(-3150 2925);
DISPLAY 0.510638 (-3150 2925);
DISPLAY INVISIBLE (-3150 2925);
FORCEADD Q_CAP..1
(-3425 3700);
FORCEPROP 1 LAST LOCATION C410
J 0
(-3375 3800);
DISPLAY 0.978723 (-3375 3800);
PAINT WHITE (-3375 3800);
FORCEPROP 0 LAST $SEC 1
J 0
(-3375 3850);
DISPLAY 0.680851 (-3375 3850);
PAINT MONO (-3375 3850);
DISPLAY INVISIBLE (-3375 3850);
FORCEPROP 0 LAST CDS_SEC 1
J 0
(-3375 3850);
DISPLAY 0.680851 (-3375 3850);
DISPLAY INVISIBLE (-3375 3850);
FORCEPROP 1 LASTPIN (-3425 3800) $PN 1
J 0
(-3415 3780);
DISPLAY 0.787234 (-3415 3780);
PAINT MONO (-3415 3780);
FORCEPROP 1 LASTPIN (-3425 3600) $PN 2
J 0
(-3415 3580);
DISPLAY 0.787234 (-3415 3580);
PAINT MONO (-3415 3580);
FORCEPROP 1 LAST PACK_TYPE C0402
J 0
(-3375 3550);
DISPLAY 0.510638 (-3375 3550);
FORCEPROP 1 LAST MATERIAL X6S
J 0
(-3375 3600);
DISPLAY 0.510638 (-3375 3600);
FORCEPROP 1 LAST VALUE 10UF
J 0
(-3375 3750);
DISPLAY 0.510638 (-3375 3750);
FORCEPROP 1 LAST TOLERANCE 20%
J 0
(-3375 3650);
DISPLAY 0.510638 (-3375 3650);
FORCEPROP 1 LAST VOLTAGE 6.3V
J 0
(-3375 3700);
DISPLAY 0.510638 (-3375 3700);
FORCEPROP 2 LAST CDS_LIB pure_quanta
J 0
(-3425 3700);
DISPLAY INVISIBLE (-3425 3700);
FORCEPROP 1 LAST PATH I44
J 0
(-3375 3850);
DISPLAY 0.978723 (-3375 3850);
PAINT WHITE (-3375 3850);
DISPLAY INVISIBLE (-3375 3850);
FORCEPROP 1 LAST PART_NUMBER CH6101MEB01
J 0
(-3375 3550);
DISPLAY 0.978723 (-3375 3550);
DISPLAY INVISIBLE (-3375 3550);
FORCEADD Q_CAP..1
(-3200 3700);
FORCEPROP 1 LAST LOCATION C420
J 0
(-3150 3800);
DISPLAY 0.978723 (-3150 3800);
PAINT WHITE (-3150 3800);
FORCEPROP 0 LAST $SEC 1
J 0
(-3150 3850);
DISPLAY 0.680851 (-3150 3850);
PAINT MONO (-3150 3850);
DISPLAY INVISIBLE (-3150 3850);
FORCEPROP 0 LAST CDS_SEC 1
J 0
(-3150 3850);
DISPLAY 0.680851 (-3150 3850);
DISPLAY INVISIBLE (-3150 3850);
FORCEPROP 1 LASTPIN (-3200 3800) $PN 1
J 0
(-3190 3780);
DISPLAY 0.787234 (-3190 3780);
PAINT MONO (-3190 3780);
FORCEPROP 1 LASTPIN (-3200 3600) $PN 2
J 0
(-3190 3580);
DISPLAY 0.787234 (-3190 3580);
PAINT MONO (-3190 3580);
FORCEPROP 1 LAST PACK_TYPE C0402
J 0
(-3150 3550);
DISPLAY 0.510638 (-3150 3550);
FORCEPROP 1 LAST VOLTAGE 6.3V
J 0
(-3150 3700);
DISPLAY 0.510638 (-3150 3700);
FORCEPROP 1 LAST VALUE 10UF
J 0
(-3150 3750);
DISPLAY 0.510638 (-3150 3750);
FORCEPROP 1 LAST TOLERANCE 20%
J 0
(-3150 3650);
DISPLAY 0.510638 (-3150 3650);
FORCEPROP 1 LAST MATERIAL X6S
J 0
(-3150 3600);
DISPLAY 0.510638 (-3150 3600);
FORCEPROP 2 LAST CDS_LIB pure_quanta
J 0
(-3200 3700);
DISPLAY INVISIBLE (-3200 3700);
FORCEPROP 1 LAST PATH I45
J 0
(-3150 3850);
DISPLAY 0.978723 (-3150 3850);
PAINT WHITE (-3150 3850);
DISPLAY INVISIBLE (-3150 3850);
FORCEPROP 1 LAST PART_NUMBER CH6101MEB01
J 0
(-3150 3550);
DISPLAY 0.978723 (-3150 3550);
DISPLAY INVISIBLE (-3150 3550);
FORCEADD Q_CAP..1
(-3425 4325);
FORCEPROP 1 LAST LOCATION C398
J 0
(-3375 4425);
DISPLAY 0.978723 (-3375 4425);
PAINT WHITE (-3375 4425);
FORCEPROP 0 LAST $SEC 1
J 0
(-3375 4475);
DISPLAY 0.680851 (-3375 4475);
PAINT MONO (-3375 4475);
DISPLAY INVISIBLE (-3375 4475);
FORCEPROP 0 LAST CDS_SEC 1
J 0
(-3375 4475);
DISPLAY 0.680851 (-3375 4475);
DISPLAY INVISIBLE (-3375 4475);
FORCEPROP 1 LASTPIN (-3425 4425) $PN 1
J 0
(-3415 4405);
DISPLAY 0.787234 (-3415 4405);
PAINT MONO (-3415 4405);
FORCEPROP 1 LASTPIN (-3425 4225) $PN 2
J 0
(-3415 4205);
DISPLAY 0.787234 (-3415 4205);
PAINT MONO (-3415 4205);
FORCEPROP 1 LAST PACK_TYPE C0805
J 0
(-3375 4175);
DISPLAY 0.510638 (-3375 4175);
FORCEPROP 1 LAST VALUE 100UF
J 0
(-3375 4375);
DISPLAY 0.510638 (-3375 4375);
FORCEPROP 1 LAST TOLERANCE 20%
J 0
(-3375 4275);
DISPLAY 0.510638 (-3375 4275);
FORCEPROP 1 LAST MATERIAL X6S
J 0
(-3375 4225);
DISPLAY 0.510638 (-3375 4225);
FORCEPROP 1 LAST VOLTAGE 4V
J 0
(-3375 4325);
DISPLAY 0.510638 (-3375 4325);
FORCEPROP 2 LAST CDS_LIB pure_quanta
J 0
(-3425 4325);
DISPLAY INVISIBLE (-3425 4325);
FORCEPROP 1 LAST PATH I46
J 0
(-3375 4475);
DISPLAY 0.978723 (-3375 4475);
PAINT WHITE (-3375 4475);
DISPLAY INVISIBLE (-3375 4475);
FORCEPROP 1 LAST PART_NUMBER CH710KMEA01
J 0
(-3375 4175);
DISPLAY 0.404255 (-3375 4175);
DISPLAY INVISIBLE (-3375 4175);
FORCEADD Q_CAP..1
(-3200 4325);
FORCEPROP 1 LAST LOCATION C401
J 0
(-3150 4425);
DISPLAY 0.978723 (-3150 4425);
PAINT WHITE (-3150 4425);
FORCEPROP 0 LAST $SEC 1
J 0
(-3150 4475);
DISPLAY 0.680851 (-3150 4475);
PAINT MONO (-3150 4475);
DISPLAY INVISIBLE (-3150 4475);
FORCEPROP 0 LAST CDS_SEC 1
J 0
(-3150 4475);
DISPLAY 0.680851 (-3150 4475);
DISPLAY INVISIBLE (-3150 4475);
FORCEPROP 1 LASTPIN (-3200 4425) $PN 1
J 0
(-3190 4405);
DISPLAY 0.787234 (-3190 4405);
PAINT MONO (-3190 4405);
FORCEPROP 1 LASTPIN (-3200 4225) $PN 2
J 0
(-3190 4205);
DISPLAY 0.787234 (-3190 4205);
PAINT MONO (-3190 4205);
FORCEPROP 1 LAST MATERIAL X6S
J 0
(-3150 4225);
DISPLAY 0.510638 (-3150 4225);
FORCEPROP 1 LAST PACK_TYPE C0805
J 0
(-3150 4175);
DISPLAY 0.510638 (-3150 4175);
FORCEPROP 1 LAST VOLTAGE 4V
J 0
(-3150 4325);
DISPLAY 0.510638 (-3150 4325);
FORCEPROP 1 LAST VALUE 100UF
J 0
(-3150 4375);
DISPLAY 0.510638 (-3150 4375);
FORCEPROP 1 LAST TOLERANCE 20%
J 0
(-3150 4275);
DISPLAY 0.510638 (-3150 4275);
FORCEPROP 2 LAST CDS_LIB pure_quanta
J 0
(-3200 4325);
DISPLAY INVISIBLE (-3200 4325);
FORCEPROP 1 LAST PATH I47
J 0
(-3150 4475);
DISPLAY 0.978723 (-3150 4475);
PAINT WHITE (-3150 4475);
DISPLAY INVISIBLE (-3150 4475);
FORCEPROP 1 LAST PART_NUMBER CH710KMEA01
J 0
(-3150 4175);
DISPLAY 0.404255 (-3150 4175);
DISPLAY INVISIBLE (-3150 4175);
FORCEADD Q_CAP..1
(-2975 3700);
FORCEPROP 1 LAST LOCATION C406
J 0
(-2925 3800);
DISPLAY 0.978723 (-2925 3800);
PAINT WHITE (-2925 3800);
FORCEPROP 0 LAST $SEC 1
J 0
(-2925 3850);
DISPLAY 0.680851 (-2925 3850);
PAINT MONO (-2925 3850);
DISPLAY INVISIBLE (-2925 3850);
FORCEPROP 0 LAST CDS_SEC 1
J 0
(-2925 3850);
DISPLAY 0.680851 (-2925 3850);
DISPLAY INVISIBLE (-2925 3850);
FORCEPROP 1 LASTPIN (-2975 3800) $PN 1
J 0
(-2965 3780);
DISPLAY 0.787234 (-2965 3780);
PAINT MONO (-2965 3780);
FORCEPROP 1 LASTPIN (-2975 3600) $PN 2
J 0
(-2965 3580);
DISPLAY 0.787234 (-2965 3580);
PAINT MONO (-2965 3580);
FORCEPROP 1 LAST MATERIAL X6S
J 0
(-2925 3600);
DISPLAY 0.510638 (-2925 3600);
FORCEPROP 1 LAST PACK_TYPE 0402
J 0
(-2925 3550);
DISPLAY 0.510638 (-2925 3550);
FORCEPROP 1 LAST VALUE 4.7UF
J 0
(-2925 3750);
DISPLAY 0.510638 (-2925 3750);
FORCEPROP 1 LAST TOLERANCE 20%
J 0
(-2925 3650);
DISPLAY 0.510638 (-2925 3650);
FORCEPROP 1 LAST VOLTAGE 6.3V
J 0
(-2925 3700);
DISPLAY 0.510638 (-2925 3700);
FORCEPROP 2 LAST CDS_LIB pure_quanta
J 0
(-2975 3700);
DISPLAY INVISIBLE (-2975 3700);
FORCEPROP 1 LAST PATH I48
J 0
(-2925 3850);
DISPLAY 0.978723 (-2925 3850);
PAINT WHITE (-2925 3850);
DISPLAY INVISIBLE (-2925 3850);
FORCEPROP 1 LAST PART_NUMBER CH5471MEB01
J 0
(-2925 3550);
DISPLAY 0.978723 (-2925 3550);
DISPLAY INVISIBLE (-2925 3550);
FORCEADD Q_CAP..1
(-2950 3075);
FORCEPROP 1 LAST LOCATION C407
J 0
(-2900 3175);
DISPLAY 0.978723 (-2900 3175);
PAINT WHITE (-2900 3175);
FORCEPROP 0 LAST $SEC 1
J 0
(-2900 3225);
DISPLAY 0.680851 (-2900 3225);
PAINT MONO (-2900 3225);
DISPLAY INVISIBLE (-2900 3225);
FORCEPROP 0 LAST CDS_SEC 1
J 0
(-2900 3225);
DISPLAY 0.680851 (-2900 3225);
DISPLAY INVISIBLE (-2900 3225);
FORCEPROP 1 LASTPIN (-2950 3175) $PN 1
J 0
(-2940 3155);
DISPLAY 0.787234 (-2940 3155);
PAINT MONO (-2940 3155);
FORCEPROP 1 LASTPIN (-2950 2975) $PN 2
J 0
(-2940 2955);
DISPLAY 0.787234 (-2940 2955);
PAINT MONO (-2940 2955);
FORCEPROP 1 LAST TOLERANCE 20%
J 0
(-2900 3025);
DISPLAY 0.510638 (-2900 3025);
FORCEPROP 1 LAST VOLTAGE 4V
J 0
(-2900 3075);
DISPLAY 0.510638 (-2900 3075);
FORCEPROP 1 LAST VALUE 1UF
J 0
(-2900 3125);
DISPLAY 0.510638 (-2900 3125);
FORCEPROP 1 LAST PACK_TYPE 0201
J 0
(-2900 2925);
DISPLAY 0.510638 (-2900 2925);
FORCEPROP 1 LAST MATERIAL X6S
J 0
(-2900 2975);
DISPLAY 0.510638 (-2900 2975);
FORCEPROP 2 LAST CDS_LIB pure_quanta
J 0
(-2950 3075);
DISPLAY INVISIBLE (-2950 3075);
FORCEPROP 1 LAST PATH I49
J 0
(-2900 3225);
DISPLAY 0.978723 (-2900 3225);
PAINT WHITE (-2900 3225);
DISPLAY INVISIBLE (-2900 3225);
FORCEPROP 1 LAST PART_NUMBER CH-10KMEE00
J 0
(-2900 2925);
DISPLAY 0.510638 (-2900 2925);
DISPLAY INVISIBLE (-2900 2925);
FORCEADD Q_CAP..1
(-7150 4325);
FORCEPROP 1 LAST LOCATION C367
J 0
(-7100 4425);
DISPLAY 0.638298 (-7100 4425);
PAINT WHITE (-7100 4425);
FORCEPROP 0 LAST $SEC 1
J 0
(-7100 4450);
DISPLAY 0.680851 (-7100 4450);
PAINT MONO (-7100 4450);
DISPLAY INVISIBLE (-7100 4450);
FORCEPROP 0 LAST CDS_SEC 1
J 0
(-7100 4450);
DISPLAY 0.680851 (-7100 4450);
DISPLAY INVISIBLE (-7100 4450);
FORCEPROP 1 LASTPIN (-7150 4425) $PN 1
J 0
(-7140 4405);
DISPLAY 0.787234 (-7140 4405);
PAINT MONO (-7140 4405);
FORCEPROP 1 LASTPIN (-7150 4225) $PN 2
J 0
(-7140 4205);
DISPLAY 0.787234 (-7140 4205);
PAINT MONO (-7140 4205);
FORCEPROP 1 LAST PACK_TYPE C0805
J 0
(-7100 4175);
DISPLAY 0.510638 (-7100 4175);
FORCEPROP 1 LAST VOLTAGE 4V
J 0
(-7100 4325);
DISPLAY 0.510638 (-7100 4325);
FORCEPROP 1 LAST TOLERANCE 20%
J 0
(-7100 4275);
DISPLAY 0.510638 (-7100 4275);
FORCEPROP 1 LAST MATERIAL X6S
J 0
(-7100 4225);
DISPLAY 0.510638 (-7100 4225);
FORCEPROP 1 LAST VALUE 100UF
J 0
(-7100 4375);
DISPLAY 0.510638 (-7100 4375);
FORCEPROP 2 LAST CDS_LIB pure_quanta
J 0
(-7150 4325);
DISPLAY INVISIBLE (-7150 4325);
FORCEPROP 1 LAST PATH I5
J 0
(-7100 4475);
DISPLAY 0.978723 (-7100 4475);
PAINT WHITE (-7100 4475);
DISPLAY INVISIBLE (-7100 4475);
FORCEPROP 1 LAST PART_NUMBER CH710KMEA01
J 0
(-7100 4175);
DISPLAY 0.404255 (-7100 4175);
DISPLAY INVISIBLE (-7100 4175);
FORCEADD Q_CAP..1
(-2725 3075);
FORCEPROP 1 LAST LOCATION C391
J 0
(-2675 3175);
DISPLAY 0.978723 (-2675 3175);
PAINT WHITE (-2675 3175);
FORCEPROP 0 LAST $SEC 1
J 0
(-2675 3225);
DISPLAY 0.680851 (-2675 3225);
PAINT MONO (-2675 3225);
DISPLAY INVISIBLE (-2675 3225);
FORCEPROP 0 LAST CDS_SEC 1
J 0
(-2675 3225);
DISPLAY 0.680851 (-2675 3225);
DISPLAY INVISIBLE (-2675 3225);
FORCEPROP 1 LASTPIN (-2725 3175) $PN 1
J 0
(-2715 3155);
DISPLAY 0.787234 (-2715 3155);
PAINT MONO (-2715 3155);
FORCEPROP 1 LASTPIN (-2725 2975) $PN 2
J 0
(-2715 2955);
DISPLAY 0.787234 (-2715 2955);
PAINT MONO (-2715 2955);
FORCEPROP 1 LAST PACK_TYPE 0201
J 0
(-2675 2925);
DISPLAY 0.510638 (-2675 2925);
FORCEPROP 1 LAST VOLTAGE 4V
J 0
(-2675 3075);
DISPLAY 0.510638 (-2675 3075);
FORCEPROP 1 LAST TOLERANCE 20%
J 0
(-2675 3025);
DISPLAY 0.510638 (-2675 3025);
FORCEPROP 1 LAST MATERIAL X6S
J 0
(-2675 2975);
DISPLAY 0.510638 (-2675 2975);
FORCEPROP 1 LAST VALUE 1UF
J 0
(-2675 3125);
DISPLAY 0.510638 (-2675 3125);
FORCEPROP 2 LAST CDS_LIB pure_quanta
J 0
(-2725 3075);
DISPLAY INVISIBLE (-2725 3075);
FORCEPROP 1 LAST PATH I50
J 0
(-2675 3225);
DISPLAY 0.978723 (-2675 3225);
PAINT WHITE (-2675 3225);
DISPLAY INVISIBLE (-2675 3225);
FORCEPROP 1 LAST PART_NUMBER CH-10KMEE00
J 0
(-2675 2925);
DISPLAY 0.510638 (-2675 2925);
DISPLAY INVISIBLE (-2675 2925);
FORCEADD Q_CAP..1
(-2475 3075);
FORCEPROP 1 LAST LOCATION C415
J 0
(-2425 3175);
DISPLAY 0.978723 (-2425 3175);
PAINT WHITE (-2425 3175);
FORCEPROP 0 LAST $SEC 1
J 0
(-2425 3225);
DISPLAY 0.680851 (-2425 3225);
PAINT MONO (-2425 3225);
DISPLAY INVISIBLE (-2425 3225);
FORCEPROP 0 LAST CDS_SEC 1
J 0
(-2425 3225);
DISPLAY 0.680851 (-2425 3225);
DISPLAY INVISIBLE (-2425 3225);
FORCEPROP 1 LASTPIN (-2475 3175) $PN 1
J 0
(-2465 3155);
DISPLAY 0.787234 (-2465 3155);
PAINT MONO (-2465 3155);
FORCEPROP 1 LASTPIN (-2475 2975) $PN 2
J 0
(-2465 2955);
DISPLAY 0.787234 (-2465 2955);
PAINT MONO (-2465 2955);
FORCEPROP 1 LAST PACK_TYPE 0201
J 0
(-2425 2925);
DISPLAY 0.510638 (-2425 2925);
FORCEPROP 1 LAST VOLTAGE 4V
J 0
(-2425 3075);
DISPLAY 0.510638 (-2425 3075);
FORCEPROP 1 LAST TOLERANCE 20%
J 0
(-2425 3025);
DISPLAY 0.510638 (-2425 3025);
FORCEPROP 1 LAST MATERIAL X6S
J 0
(-2425 2975);
DISPLAY 0.510638 (-2425 2975);
FORCEPROP 1 LAST VALUE 1UF
J 0
(-2425 3125);
DISPLAY 0.510638 (-2425 3125);
FORCEPROP 2 LAST CDS_LIB pure_quanta
J 0
(-2475 3075);
DISPLAY INVISIBLE (-2475 3075);
FORCEPROP 1 LAST PATH I51
J 0
(-2425 3225);
DISPLAY 0.978723 (-2425 3225);
PAINT WHITE (-2425 3225);
DISPLAY INVISIBLE (-2425 3225);
FORCEPROP 1 LAST PART_NUMBER CH-10KMEE00
J 0
(-2425 2925);
DISPLAY 0.510638 (-2425 2925);
DISPLAY INVISIBLE (-2425 2925);
FORCEADD Q_CAP..1
(-2250 3050);
FORCEPROP 1 LAST LOCATION C418
J 0
(-2200 3150);
DISPLAY 0.978723 (-2200 3150);
PAINT WHITE (-2200 3150);
FORCEPROP 0 LAST $SEC 1
J 0
(-2200 3200);
DISPLAY 0.680851 (-2200 3200);
PAINT MONO (-2200 3200);
DISPLAY INVISIBLE (-2200 3200);
FORCEPROP 0 LAST CDS_SEC 1
J 0
(-2200 3200);
DISPLAY 0.680851 (-2200 3200);
DISPLAY INVISIBLE (-2200 3200);
FORCEPROP 1 LASTPIN (-2250 3150) $PN 1
J 0
(-2240 3130);
DISPLAY 0.787234 (-2240 3130);
PAINT MONO (-2240 3130);
FORCEPROP 1 LASTPIN (-2250 2950) $PN 2
J 0
(-2240 2930);
DISPLAY 0.787234 (-2240 2930);
PAINT MONO (-2240 2930);
FORCEPROP 1 LAST PACK_TYPE 0201
J 0
(-2200 2900);
DISPLAY 0.510638 (-2200 2900);
FORCEPROP 1 LAST MATERIAL X6S
J 0
(-2200 2950);
DISPLAY 0.510638 (-2200 2950);
FORCEPROP 1 LAST VOLTAGE 4V
J 0
(-2200 3050);
DISPLAY 0.510638 (-2200 3050);
FORCEPROP 1 LAST TOLERANCE 20%
J 0
(-2200 3000);
DISPLAY 0.510638 (-2200 3000);
FORCEPROP 1 LAST VALUE 1UF
J 0
(-2200 3100);
DISPLAY 0.510638 (-2200 3100);
FORCEPROP 2 LAST CDS_LIB pure_quanta
J 0
(-2250 3050);
DISPLAY INVISIBLE (-2250 3050);
FORCEPROP 1 LAST PATH I52
J 0
(-2200 3200);
DISPLAY 0.978723 (-2200 3200);
PAINT WHITE (-2200 3200);
DISPLAY INVISIBLE (-2200 3200);
FORCEPROP 1 LAST PART_NUMBER CH-10KMEE00
J 0
(-2200 2900);
DISPLAY 0.510638 (-2200 2900);
DISPLAY INVISIBLE (-2200 2900);
FORCEADD Q_CAP..1
(-2025 3050);
FORCEPROP 1 LAST LOCATION C422
J 0
(-1975 3150);
DISPLAY 0.978723 (-1975 3150);
PAINT WHITE (-1975 3150);
FORCEPROP 0 LAST $SEC 1
J 0
(-1975 3200);
DISPLAY 0.680851 (-1975 3200);
PAINT MONO (-1975 3200);
DISPLAY INVISIBLE (-1975 3200);
FORCEPROP 0 LAST CDS_SEC 1
J 0
(-1975 3200);
DISPLAY 0.680851 (-1975 3200);
DISPLAY INVISIBLE (-1975 3200);
FORCEPROP 1 LASTPIN (-2025 3150) $PN 1
J 0
(-2015 3130);
DISPLAY 0.787234 (-2015 3130);
PAINT MONO (-2015 3130);
FORCEPROP 1 LASTPIN (-2025 2950) $PN 2
J 0
(-2015 2930);
DISPLAY 0.787234 (-2015 2930);
PAINT MONO (-2015 2930);
FORCEPROP 1 LAST VALUE 1UF
J 0
(-1975 3100);
DISPLAY 0.510638 (-1975 3100);
FORCEPROP 1 LAST TOLERANCE 20%
J 0
(-1975 3000);
DISPLAY 0.510638 (-1975 3000);
FORCEPROP 1 LAST MATERIAL X6S
J 0
(-1975 2950);
DISPLAY 0.510638 (-1975 2950);
FORCEPROP 1 LAST VOLTAGE 4V
J 0
(-1975 3050);
DISPLAY 0.510638 (-1975 3050);
FORCEPROP 1 LAST PACK_TYPE 0201
J 0
(-1975 2900);
DISPLAY 0.510638 (-1975 2900);
FORCEPROP 2 LAST CDS_LIB pure_quanta
J 0
(-2025 3050);
DISPLAY INVISIBLE (-2025 3050);
FORCEPROP 1 LAST PATH I53
J 0
(-1975 3200);
DISPLAY 0.978723 (-1975 3200);
PAINT WHITE (-1975 3200);
DISPLAY INVISIBLE (-1975 3200);
FORCEPROP 1 LAST PART_NUMBER CH-10KMEE00
J 0
(-1975 2900);
DISPLAY 0.510638 (-1975 2900);
DISPLAY INVISIBLE (-1975 2900);
FORCEADD Q_CAP..1
(-2750 3700);
FORCEPROP 1 LAST LOCATION C416
J 0
(-2700 3800);
DISPLAY 0.978723 (-2700 3800);
PAINT WHITE (-2700 3800);
FORCEPROP 0 LAST $SEC 1
J 0
(-2700 3850);
DISPLAY 0.680851 (-2700 3850);
PAINT MONO (-2700 3850);
DISPLAY INVISIBLE (-2700 3850);
FORCEPROP 0 LAST CDS_SEC 1
J 0
(-2700 3850);
DISPLAY 0.680851 (-2700 3850);
DISPLAY INVISIBLE (-2700 3850);
FORCEPROP 1 LASTPIN (-2750 3800) $PN 1
J 0
(-2740 3780);
DISPLAY 0.787234 (-2740 3780);
PAINT MONO (-2740 3780);
FORCEPROP 1 LASTPIN (-2750 3600) $PN 2
J 0
(-2740 3580);
DISPLAY 0.787234 (-2740 3580);
PAINT MONO (-2740 3580);
FORCEPROP 1 LAST VALUE 4.7UF
J 0
(-2700 3750);
DISPLAY 0.510638 (-2700 3750);
FORCEPROP 1 LAST PACK_TYPE 0402
J 0
(-2700 3550);
DISPLAY 0.510638 (-2700 3550);
FORCEPROP 1 LAST VOLTAGE 6.3V
J 0
(-2700 3700);
DISPLAY 0.510638 (-2700 3700);
FORCEPROP 1 LAST TOLERANCE 20%
J 0
(-2700 3650);
DISPLAY 0.510638 (-2700 3650);
FORCEPROP 1 LAST MATERIAL X6S
J 0
(-2700 3600);
DISPLAY 0.510638 (-2700 3600);
FORCEPROP 2 LAST CDS_LIB pure_quanta
J 0
(-2750 3700);
DISPLAY INVISIBLE (-2750 3700);
FORCEPROP 1 LAST PATH I54
J 0
(-2700 3850);
DISPLAY 0.978723 (-2700 3850);
PAINT WHITE (-2700 3850);
DISPLAY INVISIBLE (-2700 3850);
FORCEPROP 1 LAST PART_NUMBER CH5471MEB01
J 0
(-2700 3550);
DISPLAY 0.978723 (-2700 3550);
DISPLAY INVISIBLE (-2700 3550);
FORCEADD Q_CAP..1
(-2500 3700);
FORCEPROP 1 LAST LOCATION C413
J 0
(-2450 3800);
DISPLAY 0.978723 (-2450 3800);
PAINT WHITE (-2450 3800);
FORCEPROP 0 LAST $SEC 1
J 0
(-2450 3850);
DISPLAY 0.680851 (-2450 3850);
PAINT MONO (-2450 3850);
DISPLAY INVISIBLE (-2450 3850);
FORCEPROP 0 LAST CDS_SEC 1
J 0
(-2450 3850);
DISPLAY 0.680851 (-2450 3850);
DISPLAY INVISIBLE (-2450 3850);
FORCEPROP 1 LASTPIN (-2500 3800) $PN 1
J 0
(-2490 3780);
DISPLAY 0.787234 (-2490 3780);
PAINT MONO (-2490 3780);
FORCEPROP 1 LASTPIN (-2500 3600) $PN 2
J 0
(-2490 3580);
DISPLAY 0.787234 (-2490 3580);
PAINT MONO (-2490 3580);
FORCEPROP 1 LAST PACK_TYPE 0402
J 0
(-2450 3550);
DISPLAY 0.510638 (-2450 3550);
FORCEPROP 1 LAST VOLTAGE 6.3V
J 0
(-2450 3700);
DISPLAY 0.510638 (-2450 3700);
FORCEPROP 1 LAST VALUE 4.7UF
J 0
(-2450 3750);
DISPLAY 0.510638 (-2450 3750);
FORCEPROP 1 LAST TOLERANCE 20%
J 0
(-2450 3650);
DISPLAY 0.510638 (-2450 3650);
FORCEPROP 1 LAST MATERIAL X6S
J 0
(-2450 3600);
DISPLAY 0.510638 (-2450 3600);
FORCEPROP 2 LAST CDS_LIB pure_quanta
J 0
(-2500 3700);
DISPLAY INVISIBLE (-2500 3700);
FORCEPROP 1 LAST PATH I55
J 0
(-2450 3850);
DISPLAY 0.978723 (-2450 3850);
PAINT WHITE (-2450 3850);
DISPLAY INVISIBLE (-2450 3850);
FORCEPROP 1 LAST PART_NUMBER CH5471MEB01
J 0
(-2450 3550);
DISPLAY 0.978723 (-2450 3550);
DISPLAY INVISIBLE (-2450 3550);
FORCEADD Q_CAP..1
(-2500 4325);
FORCEPROP 1 LAST LOCATION C417
J 0
(-2450 4425);
DISPLAY 0.978723 (-2450 4425);
PAINT WHITE (-2450 4425);
FORCEPROP 0 LAST $SEC 1
J 0
(-2450 4475);
DISPLAY 0.680851 (-2450 4475);
PAINT MONO (-2450 4475);
DISPLAY INVISIBLE (-2450 4475);
FORCEPROP 0 LAST CDS_SEC 1
J 0
(-2450 4475);
DISPLAY 0.680851 (-2450 4475);
DISPLAY INVISIBLE (-2450 4475);
FORCEPROP 1 LASTPIN (-2500 4425) $PN 1
J 0
(-2490 4405);
DISPLAY 0.787234 (-2490 4405);
PAINT MONO (-2490 4405);
FORCEPROP 1 LASTPIN (-2500 4225) $PN 2
J 0
(-2490 4205);
DISPLAY 0.787234 (-2490 4205);
PAINT MONO (-2490 4205);
FORCEPROP 1 LAST PACK_TYPE C0402
J 0
(-2450 4175);
DISPLAY 0.510638 (-2450 4175);
FORCEPROP 1 LAST MATERIAL X6S
J 0
(-2450 4225);
DISPLAY 0.510638 (-2450 4225);
FORCEPROP 1 LAST TOLERANCE 20%
J 0
(-2450 4275);
DISPLAY 0.510638 (-2450 4275);
FORCEPROP 1 LAST VOLTAGE 4V
J 0
(-2450 4325);
DISPLAY 0.510638 (-2450 4325);
FORCEPROP 1 LAST VALUE 22UF
J 0
(-2450 4375);
DISPLAY 0.510638 (-2450 4375);
FORCEPROP 2 LAST CDS_LIB pure_quanta
J 0
(-2500 4325);
DISPLAY INVISIBLE (-2500 4325);
FORCEPROP 1 LAST PATH I56
J 0
(-2450 4475);
DISPLAY 0.978723 (-2450 4475);
PAINT WHITE (-2450 4475);
DISPLAY INVISIBLE (-2450 4475);
FORCEPROP 1 LAST PART_NUMBER CH622KMEB02
J 0
(-2450 4175);
DISPLAY 0.978723 (-2450 4175);
DISPLAY INVISIBLE (-2450 4175);
FORCEADD Q_CAP..1
(-2275 3700);
FORCEPROP 1 LAST LOCATION C412
J 0
(-2225 3800);
DISPLAY 0.978723 (-2225 3800);
PAINT WHITE (-2225 3800);
FORCEPROP 0 LAST $SEC 1
J 0
(-2225 3850);
DISPLAY 0.680851 (-2225 3850);
PAINT MONO (-2225 3850);
DISPLAY INVISIBLE (-2225 3850);
FORCEPROP 0 LAST CDS_SEC 1
J 0
(-2225 3850);
DISPLAY 0.680851 (-2225 3850);
DISPLAY INVISIBLE (-2225 3850);
FORCEPROP 1 LASTPIN (-2275 3800) $PN 1
J 0
(-2265 3780);
DISPLAY 0.787234 (-2265 3780);
PAINT MONO (-2265 3780);
FORCEPROP 1 LASTPIN (-2275 3600) $PN 2
J 0
(-2265 3580);
DISPLAY 0.787234 (-2265 3580);
PAINT MONO (-2265 3580);
FORCEPROP 1 LAST VALUE 4.7UF
J 0
(-2225 3750);
DISPLAY 0.510638 (-2225 3750);
FORCEPROP 1 LAST PACK_TYPE 0402
J 0
(-2225 3550);
DISPLAY 0.510638 (-2225 3550);
FORCEPROP 1 LAST MATERIAL X6S
J 0
(-2225 3600);
DISPLAY 0.510638 (-2225 3600);
FORCEPROP 1 LAST TOLERANCE 20%
J 0
(-2225 3650);
DISPLAY 0.510638 (-2225 3650);
FORCEPROP 1 LAST VOLTAGE 6.3V
J 0
(-2225 3700);
DISPLAY 0.510638 (-2225 3700);
FORCEPROP 2 LAST CDS_LIB pure_quanta
J 0
(-2275 3700);
DISPLAY INVISIBLE (-2275 3700);
FORCEPROP 1 LAST PATH I57
J 0
(-2225 3850);
DISPLAY 0.978723 (-2225 3850);
PAINT WHITE (-2225 3850);
DISPLAY INVISIBLE (-2225 3850);
FORCEPROP 1 LAST PART_NUMBER CH5471MEB01
J 0
(-2225 3550);
DISPLAY 0.978723 (-2225 3550);
DISPLAY INVISIBLE (-2225 3550);
FORCEADD Q_CAP..1
(-2050 3700);
FORCEPROP 1 LAST LOCATION C386
J 0
(-2000 3800);
DISPLAY 0.978723 (-2000 3800);
PAINT WHITE (-2000 3800);
FORCEPROP 0 LAST $SEC 1
J 0
(-2000 3850);
DISPLAY 0.680851 (-2000 3850);
PAINT MONO (-2000 3850);
DISPLAY INVISIBLE (-2000 3850);
FORCEPROP 0 LAST CDS_SEC 1
J 0
(-2000 3850);
DISPLAY 0.680851 (-2000 3850);
DISPLAY INVISIBLE (-2000 3850);
FORCEPROP 1 LASTPIN (-2050 3800) $PN 1
J 0
(-2040 3780);
DISPLAY 0.787234 (-2040 3780);
PAINT MONO (-2040 3780);
FORCEPROP 1 LASTPIN (-2050 3600) $PN 2
J 0
(-2040 3580);
DISPLAY 0.787234 (-2040 3580);
PAINT MONO (-2040 3580);
FORCEPROP 1 LAST TOLERANCE 20%
J 0
(-2000 3650);
DISPLAY 0.510638 (-2000 3650);
FORCEPROP 1 LAST PACK_TYPE 0201
J 0
(-2000 3550);
DISPLAY 0.510638 (-2000 3550);
FORCEPROP 1 LAST VOLTAGE 4V
J 0
(-2000 3700);
DISPLAY 0.510638 (-2000 3700);
FORCEPROP 1 LAST VALUE 1UF
J 0
(-2000 3750);
DISPLAY 0.510638 (-2000 3750);
FORCEPROP 1 LAST MATERIAL X6S
J 0
(-2000 3600);
DISPLAY 0.510638 (-2000 3600);
FORCEPROP 2 LAST CDS_LIB pure_quanta
J 0
(-2050 3700);
DISPLAY INVISIBLE (-2050 3700);
FORCEPROP 1 LAST PATH I58
J 0
(-2000 3850);
DISPLAY 0.978723 (-2000 3850);
PAINT WHITE (-2000 3850);
DISPLAY INVISIBLE (-2000 3850);
FORCEPROP 1 LAST PART_NUMBER CH-10KMEE00
J 0
(-2000 3550);
DISPLAY 0.510638 (-2000 3550);
DISPLAY INVISIBLE (-2000 3550);
FORCEADD Q_CAP..1
(-2275 4325);
FORCEPROP 1 LAST LOCATION C399
J 0
(-2225 4425);
DISPLAY 0.978723 (-2225 4425);
PAINT WHITE (-2225 4425);
FORCEPROP 0 LAST $SEC 1
J 0
(-2225 4475);
DISPLAY 0.680851 (-2225 4475);
PAINT MONO (-2225 4475);
DISPLAY INVISIBLE (-2225 4475);
FORCEPROP 0 LAST CDS_SEC 1
J 0
(-2225 4475);
DISPLAY 0.680851 (-2225 4475);
DISPLAY INVISIBLE (-2225 4475);
FORCEPROP 1 LASTPIN (-2275 4425) $PN 1
J 0
(-2265 4405);
DISPLAY 0.787234 (-2265 4405);
PAINT MONO (-2265 4405);
FORCEPROP 1 LASTPIN (-2275 4225) $PN 2
J 0
(-2265 4205);
DISPLAY 0.787234 (-2265 4205);
PAINT MONO (-2265 4205);
FORCEPROP 1 LAST VALUE 22UF
J 0
(-2225 4375);
DISPLAY 0.510638 (-2225 4375);
FORCEPROP 1 LAST TOLERANCE 20%
J 0
(-2225 4275);
DISPLAY 0.510638 (-2225 4275);
FORCEPROP 1 LAST MATERIAL X6S
J 0
(-2225 4225);
DISPLAY 0.510638 (-2225 4225);
FORCEPROP 1 LAST PACK_TYPE C0402
J 0
(-2225 4175);
DISPLAY 0.510638 (-2225 4175);
FORCEPROP 1 LAST VOLTAGE 4V
J 0
(-2225 4325);
DISPLAY 0.510638 (-2225 4325);
FORCEPROP 2 LAST CDS_LIB pure_quanta
J 0
(-2275 4325);
DISPLAY INVISIBLE (-2275 4325);
FORCEPROP 1 LAST PATH I59
J 0
(-2225 4475);
DISPLAY 0.978723 (-2225 4475);
PAINT WHITE (-2225 4475);
DISPLAY INVISIBLE (-2225 4475);
FORCEPROP 1 LAST PART_NUMBER CH622KMEB02
J 0
(-2225 4175);
DISPLAY 0.978723 (-2225 4175);
DISPLAY INVISIBLE (-2225 4175);
FORCEADD Q_CAP..1
(-6725 3250);
FORCEPROP 1 LAST LOCATION C375
J 0
(-6675 3350);
DISPLAY 0.638298 (-6675 3350);
PAINT WHITE (-6675 3350);
FORCEPROP 0 LAST $SEC 1
J 0
(-6675 3400);
DISPLAY 0.680851 (-6675 3400);
PAINT MONO (-6675 3400);
DISPLAY INVISIBLE (-6675 3400);
FORCEPROP 0 LAST CDS_SEC 1
J 0
(-6675 3400);
DISPLAY 0.680851 (-6675 3400);
DISPLAY INVISIBLE (-6675 3400);
FORCEPROP 1 LASTPIN (-6725 3350) $PN 1
J 0
(-6715 3330);
DISPLAY 0.787234 (-6715 3330);
PAINT MONO (-6715 3330);
FORCEPROP 1 LASTPIN (-6725 3150) $PN 2
J 0
(-6715 3130);
DISPLAY 0.787234 (-6715 3130);
PAINT MONO (-6715 3130);
FORCEPROP 1 LAST PACK_TYPE 0201
J 0
(-6675 3100);
DISPLAY 0.510638 (-6675 3100);
FORCEPROP 1 LAST MATERIAL X6S
J 0
(-6675 3150);
DISPLAY 0.510638 (-6675 3150);
FORCEPROP 1 LAST VOLTAGE 4V
J 0
(-6675 3250);
DISPLAY 0.510638 (-6675 3250);
FORCEPROP 1 LAST TOLERANCE 20%
J 0
(-6675 3200);
DISPLAY 0.510638 (-6675 3200);
FORCEPROP 1 LAST VALUE 1UF
J 0
(-6675 3300);
DISPLAY 0.510638 (-6675 3300);
FORCEPROP 2 LAST CDS_LIB pure_quanta
J 0
(-6725 3250);
DISPLAY INVISIBLE (-6725 3250);
FORCEPROP 1 LAST PATH I6
J 0
(-6675 3400);
DISPLAY 0.978723 (-6675 3400);
PAINT WHITE (-6675 3400);
DISPLAY INVISIBLE (-6675 3400);
FORCEPROP 1 LAST PART_NUMBER CH-10KMEE00
J 0
(-6675 3100);
DISPLAY 0.510638 (-6675 3100);
DISPLAY INVISIBLE (-6675 3100);
FORCEADD Q_CAP..1
(-2050 4325);
FORCEPROP 1 LAST LOCATION C402
J 0
(-2000 4425);
DISPLAY 0.978723 (-2000 4425);
PAINT WHITE (-2000 4425);
FORCEPROP 0 LAST $SEC 1
J 0
(-2000 4475);
DISPLAY 0.680851 (-2000 4475);
PAINT MONO (-2000 4475);
DISPLAY INVISIBLE (-2000 4475);
FORCEPROP 0 LAST CDS_SEC 1
J 0
(-2000 4475);
DISPLAY 0.680851 (-2000 4475);
DISPLAY INVISIBLE (-2000 4475);
FORCEPROP 1 LASTPIN (-2050 4425) $PN 1
J 0
(-2040 4405);
DISPLAY 0.787234 (-2040 4405);
PAINT MONO (-2040 4405);
FORCEPROP 1 LASTPIN (-2050 4225) $PN 2
J 0
(-2040 4205);
DISPLAY 0.787234 (-2040 4205);
PAINT MONO (-2040 4205);
FORCEPROP 1 LAST PACK_TYPE C0402
J 0
(-2000 4175);
DISPLAY 0.510638 (-2000 4175);
FORCEPROP 1 LAST TOLERANCE 20%
J 0
(-2000 4275);
DISPLAY 0.510638 (-2000 4275);
FORCEPROP 1 LAST MATERIAL X6S
J 0
(-2000 4225);
DISPLAY 0.510638 (-2000 4225);
FORCEPROP 1 LAST VALUE 22UF
J 0
(-2000 4375);
DISPLAY 0.510638 (-2000 4375);
FORCEPROP 1 LAST VOLTAGE 4V
J 0
(-2000 4325);
DISPLAY 0.510638 (-2000 4325);
FORCEPROP 2 LAST CDS_LIB pure_quanta
J 0
(-2050 4325);
DISPLAY INVISIBLE (-2050 4325);
FORCEPROP 1 LAST PATH I60
J 0
(-2000 4475);
DISPLAY 0.978723 (-2000 4475);
PAINT WHITE (-2000 4475);
DISPLAY INVISIBLE (-2000 4475);
FORCEPROP 1 LAST PART_NUMBER CH622KMEB02
J 0
(-2000 4175);
DISPLAY 0.978723 (-2000 4175);
DISPLAY INVISIBLE (-2000 4175);
FORCEADD Q_CAP..1
(-1850 2375);
FORCEPROP 1 LAST LOCATION C403
J 0
(-1800 2475);
DISPLAY 0.978723 (-1800 2475);
PAINT WHITE (-1800 2475);
FORCEPROP 0 LAST $SEC 1
J 0
(-1800 2525);
DISPLAY 0.680851 (-1800 2525);
PAINT MONO (-1800 2525);
DISPLAY INVISIBLE (-1800 2525);
FORCEPROP 0 LAST CDS_SEC 1
J 0
(-1800 2525);
DISPLAY 0.680851 (-1800 2525);
DISPLAY INVISIBLE (-1800 2525);
FORCEPROP 1 LASTPIN (-1850 2475) $PN 1
J 0
(-1840 2455);
DISPLAY 0.787234 (-1840 2455);
PAINT MONO (-1840 2455);
FORCEPROP 1 LASTPIN (-1850 2275) $PN 2
J 0
(-1840 2255);
DISPLAY 0.787234 (-1840 2255);
PAINT MONO (-1840 2255);
FORCEPROP 1 LAST VOLTAGE 10V
J 0
(-1800 2375);
DISPLAY 0.638298 (-1800 2375);
FORCEPROP 1 LAST VALUE 0.1UF
J 0
(-1800 2425);
DISPLAY 0.638298 (-1800 2425);
FORCEPROP 1 LAST TOLERANCE 10%
J 0
(-1800 2325);
DISPLAY 0.638298 (-1800 2325);
FORCEPROP 1 LAST MATERIAL X7S
J 0
(-1800 2275);
DISPLAY 0.638298 (-1800 2275);
FORCEPROP 1 LAST PACK_TYPE C0201
J 0
(-1800 2225);
DISPLAY 0.638298 (-1800 2225);
FORCEPROP 2 LAST CDS_LIB pure_quanta
J 0
(-1850 2375);
DISPLAY INVISIBLE (-1850 2375);
FORCEPROP 1 LAST PATH I61
J 0
(-1800 2525);
DISPLAY 0.978723 (-1800 2525);
PAINT WHITE (-1800 2525);
DISPLAY INVISIBLE (-1800 2525);
FORCEPROP 1 LAST PART_NUMBER CH4102K6E00
J 0
(-1800 2225);
DISPLAY 0.978723 (-1800 2225);
DISPLAY INVISIBLE (-1800 2225);
FORCEADD Q_CAP..1
(-1575 2375);
FORCEPROP 1 LAST LOCATION C411
J 0
(-1525 2475);
DISPLAY 0.978723 (-1525 2475);
PAINT WHITE (-1525 2475);
FORCEPROP 0 LAST $SEC 1
J 0
(-1525 2525);
DISPLAY 0.680851 (-1525 2525);
PAINT MONO (-1525 2525);
DISPLAY INVISIBLE (-1525 2525);
FORCEPROP 0 LAST CDS_SEC 1
J 0
(-1525 2525);
DISPLAY 0.680851 (-1525 2525);
DISPLAY INVISIBLE (-1525 2525);
FORCEPROP 1 LASTPIN (-1575 2475) $PN 1
J 0
(-1565 2455);
DISPLAY 0.787234 (-1565 2455);
PAINT MONO (-1565 2455);
FORCEPROP 1 LASTPIN (-1575 2275) $PN 2
J 0
(-1565 2255);
DISPLAY 0.787234 (-1565 2255);
PAINT MONO (-1565 2255);
FORCEPROP 1 LAST VOLTAGE 10V
J 0
(-1525 2375);
DISPLAY 0.638298 (-1525 2375);
FORCEPROP 1 LAST VALUE 0.1UF
J 0
(-1525 2425);
DISPLAY 0.638298 (-1525 2425);
FORCEPROP 1 LAST TOLERANCE 10%
J 0
(-1525 2325);
DISPLAY 0.638298 (-1525 2325);
FORCEPROP 1 LAST MATERIAL X7S
J 0
(-1525 2275);
DISPLAY 0.638298 (-1525 2275);
FORCEPROP 1 LAST PACK_TYPE C0201
J 0
(-1525 2225);
DISPLAY 0.638298 (-1525 2225);
FORCEPROP 2 LAST CDS_LIB pure_quanta
J 0
(-1575 2375);
DISPLAY INVISIBLE (-1575 2375);
FORCEPROP 1 LAST PATH I62
J 0
(-1525 2525);
DISPLAY 0.978723 (-1525 2525);
PAINT WHITE (-1525 2525);
DISPLAY INVISIBLE (-1525 2525);
FORCEPROP 1 LAST PART_NUMBER CH4102K6E00
J 0
(-1525 2225);
DISPLAY 0.978723 (-1525 2225);
DISPLAY INVISIBLE (-1525 2225);
FORCEADD UNIVERSAL_GND..1
(-1325 1950);
FORCEPROP 3 LASTPIN (-1325 2000) SIG_NAME GND\g
J 0
(-1315 2010);
DISPLAY 0.659574 (-1315 2010);
PAINT MONO (-1315 2010);
DISPLAY INVISIBLE (-1315 2010);
FORCEPROP 2 LAST CDS_LIB pure_quanta_power
J 0
(-1325 1950);
DISPLAY INVISIBLE (-1325 1950);
FORCEPROP 1 LAST HDL_POWER GND
J 1
(-1300 1875);
DISPLAY 0.872340 (-1300 1875);
PAINT GREEN (-1300 1875);
DISPLAY INVISIBLE (-1300 1875);
FORCEPROP 1 LAST PATH I63
J 0
(-1250 1950);
DISPLAY 0.872340 (-1250 1950);
PAINT AQUA (-1250 1950);
DISPLAY INVISIBLE (-1250 1950);
FORCEADD Q_CAP..1
(-1325 2375);
FORCEPROP 1 LAST LOCATION C395
J 0
(-1275 2475);
DISPLAY 0.978723 (-1275 2475);
PAINT WHITE (-1275 2475);
FORCEPROP 0 LAST $SEC 1
J 0
(-1275 2525);
DISPLAY 0.680851 (-1275 2525);
PAINT MONO (-1275 2525);
DISPLAY INVISIBLE (-1275 2525);
FORCEPROP 0 LAST CDS_SEC 1
J 0
(-1275 2525);
DISPLAY 0.680851 (-1275 2525);
DISPLAY INVISIBLE (-1275 2525);
FORCEPROP 1 LASTPIN (-1325 2475) $PN 1
J 0
(-1315 2455);
DISPLAY 0.787234 (-1315 2455);
PAINT MONO (-1315 2455);
FORCEPROP 1 LASTPIN (-1325 2275) $PN 2
J 0
(-1315 2255);
DISPLAY 0.787234 (-1315 2255);
PAINT MONO (-1315 2255);
FORCEPROP 1 LAST PACK_TYPE C0201
J 0
(-1275 2225);
DISPLAY 0.638298 (-1275 2225);
FORCEPROP 1 LAST VOLTAGE 10V
J 0
(-1275 2375);
DISPLAY 0.638298 (-1275 2375);
FORCEPROP 1 LAST VALUE 0.1UF
J 0
(-1275 2425);
DISPLAY 0.638298 (-1275 2425);
FORCEPROP 1 LAST TOLERANCE 10%
J 0
(-1275 2325);
DISPLAY 0.638298 (-1275 2325);
FORCEPROP 1 LAST MATERIAL X7S
J 0
(-1275 2275);
DISPLAY 0.638298 (-1275 2275);
FORCEPROP 2 LAST CDS_LIB pure_quanta
J 0
(-1325 2375);
DISPLAY INVISIBLE (-1325 2375);
FORCEPROP 1 LAST PATH I64
J 0
(-1275 2525);
DISPLAY 0.978723 (-1275 2525);
PAINT WHITE (-1275 2525);
DISPLAY INVISIBLE (-1275 2525);
FORCEPROP 1 LAST PART_NUMBER CH4102K6E00
J 0
(-1275 2225);
DISPLAY 0.978723 (-1275 2225);
DISPLAY INVISIBLE (-1275 2225);
FORCEADD Q_CAP..1
(-1825 3700);
FORCEPROP 1 LAST LOCATION C425
J 0
(-1775 3800);
DISPLAY 0.978723 (-1775 3800);
PAINT WHITE (-1775 3800);
FORCEPROP 0 LAST $SEC 1
J 0
(-1775 3850);
DISPLAY 0.680851 (-1775 3850);
PAINT MONO (-1775 3850);
DISPLAY INVISIBLE (-1775 3850);
FORCEPROP 0 LAST CDS_SEC 1
J 0
(-1775 3850);
DISPLAY 0.680851 (-1775 3850);
DISPLAY INVISIBLE (-1775 3850);
FORCEPROP 1 LASTPIN (-1825 3800) $PN 1
J 0
(-1815 3780);
DISPLAY 0.787234 (-1815 3780);
PAINT MONO (-1815 3780);
FORCEPROP 1 LASTPIN (-1825 3600) $PN 2
J 0
(-1815 3580);
DISPLAY 0.787234 (-1815 3580);
PAINT MONO (-1815 3580);
FORCEPROP 1 LAST MATERIAL X6S
J 0
(-1775 3600);
DISPLAY 0.510638 (-1775 3600);
FORCEPROP 1 LAST PACK_TYPE 0201
J 0
(-1775 3550);
DISPLAY 0.510638 (-1775 3550);
FORCEPROP 1 LAST TOLERANCE 20%
J 0
(-1775 3650);
DISPLAY 0.510638 (-1775 3650);
FORCEPROP 1 LAST VOLTAGE 4V
J 0
(-1775 3700);
DISPLAY 0.510638 (-1775 3700);
FORCEPROP 1 LAST VALUE 1UF
J 0
(-1775 3750);
DISPLAY 0.510638 (-1775 3750);
FORCEPROP 2 LAST CDS_LIB pure_quanta
J 0
(-1825 3700);
DISPLAY INVISIBLE (-1825 3700);
FORCEPROP 1 LAST PATH I67
J 0
(-1775 3850);
DISPLAY 0.978723 (-1775 3850);
PAINT WHITE (-1775 3850);
DISPLAY INVISIBLE (-1775 3850);
FORCEPROP 1 LAST PART_NUMBER CH-10KMEE00
J 0
(-1775 3550);
DISPLAY 0.510638 (-1775 3550);
DISPLAY INVISIBLE (-1775 3550);
FORCEADD Q_CAP..1
(-1600 3700);
FORCEPROP 1 LAST LOCATION C389
J 0
(-1550 3800);
DISPLAY 0.978723 (-1550 3800);
PAINT WHITE (-1550 3800);
FORCEPROP 0 LAST $SEC 1
J 0
(-1550 3850);
DISPLAY 0.680851 (-1550 3850);
PAINT MONO (-1550 3850);
DISPLAY INVISIBLE (-1550 3850);
FORCEPROP 0 LAST CDS_SEC 1
J 0
(-1550 3850);
DISPLAY 0.680851 (-1550 3850);
DISPLAY INVISIBLE (-1550 3850);
FORCEPROP 1 LASTPIN (-1600 3800) $PN 1
J 0
(-1590 3780);
DISPLAY 0.787234 (-1590 3780);
PAINT MONO (-1590 3780);
FORCEPROP 1 LASTPIN (-1600 3600) $PN 2
J 0
(-1590 3580);
DISPLAY 0.787234 (-1590 3580);
PAINT MONO (-1590 3580);
FORCEPROP 1 LAST PACK_TYPE 0201
J 0
(-1550 3550);
DISPLAY 0.510638 (-1550 3550);
FORCEPROP 1 LAST TOLERANCE 20%
J 0
(-1550 3650);
DISPLAY 0.510638 (-1550 3650);
FORCEPROP 1 LAST VOLTAGE 4V
J 0
(-1550 3700);
DISPLAY 0.510638 (-1550 3700);
FORCEPROP 1 LAST VALUE 1UF
J 0
(-1550 3750);
DISPLAY 0.510638 (-1550 3750);
FORCEPROP 1 LAST MATERIAL X6S
J 0
(-1550 3600);
DISPLAY 0.510638 (-1550 3600);
FORCEPROP 2 LAST CDS_LIB pure_quanta
J 0
(-1600 3700);
DISPLAY INVISIBLE (-1600 3700);
FORCEPROP 1 LAST PATH I68
J 0
(-1550 3850);
DISPLAY 0.978723 (-1550 3850);
PAINT WHITE (-1550 3850);
DISPLAY INVISIBLE (-1550 3850);
FORCEPROP 1 LAST PART_NUMBER CH-10KMEE00
J 0
(-1550 3550);
DISPLAY 0.510638 (-1550 3550);
DISPLAY INVISIBLE (-1550 3550);
FORCEADD Q_CAP..1
(-1825 4325);
FORCEPROP 1 LAST LOCATION C424
J 0
(-1775 4425);
DISPLAY 0.978723 (-1775 4425);
PAINT WHITE (-1775 4425);
FORCEPROP 0 LAST $SEC 1
J 0
(-1775 4475);
DISPLAY 0.680851 (-1775 4475);
PAINT MONO (-1775 4475);
DISPLAY INVISIBLE (-1775 4475);
FORCEPROP 0 LAST CDS_SEC 1
J 0
(-1775 4475);
DISPLAY 0.680851 (-1775 4475);
DISPLAY INVISIBLE (-1775 4475);
FORCEPROP 1 LASTPIN (-1825 4425) $PN 1
J 0
(-1815 4405);
DISPLAY 0.787234 (-1815 4405);
PAINT MONO (-1815 4405);
FORCEPROP 1 LASTPIN (-1825 4225) $PN 2
J 0
(-1815 4205);
DISPLAY 0.787234 (-1815 4205);
PAINT MONO (-1815 4205);
FORCEPROP 1 LAST MATERIAL X6S
J 0
(-1775 4225);
DISPLAY 0.510638 (-1775 4225);
FORCEPROP 1 LAST TOLERANCE 20%
J 0
(-1775 4275);
DISPLAY 0.510638 (-1775 4275);
FORCEPROP 1 LAST VALUE 22UF
J 0
(-1775 4375);
DISPLAY 0.510638 (-1775 4375);
FORCEPROP 1 LAST PACK_TYPE C0402
J 0
(-1775 4175);
DISPLAY 0.510638 (-1775 4175);
FORCEPROP 1 LAST VOLTAGE 4V
J 0
(-1775 4325);
DISPLAY 0.510638 (-1775 4325);
FORCEPROP 2 LAST CDS_LIB pure_quanta
J 0
(-1825 4325);
DISPLAY INVISIBLE (-1825 4325);
FORCEPROP 1 LAST PATH I69
J 0
(-1775 4475);
DISPLAY 0.978723 (-1775 4475);
PAINT WHITE (-1775 4475);
DISPLAY INVISIBLE (-1775 4475);
FORCEPROP 1 LAST PART_NUMBER CH622KMEB02
J 0
(-1775 4175);
DISPLAY 0.978723 (-1775 4175);
DISPLAY INVISIBLE (-1775 4175);
FORCEADD UNIVERSAL_GND..1
(-6450 2825);
FORCEPROP 3 LASTPIN (-6450 2875) SIG_NAME GND\g
J 0
(-6440 2885);
DISPLAY 0.659574 (-6440 2885);
PAINT MONO (-6440 2885);
DISPLAY INVISIBLE (-6440 2885);
FORCEPROP 2 LAST CDS_LIB pure_quanta_power
J 0
(-6450 2825);
DISPLAY INVISIBLE (-6450 2825);
FORCEPROP 1 LAST HDL_POWER GND
J 1
(-6425 2750);
DISPLAY 0.872340 (-6425 2750);
PAINT GREEN (-6425 2750);
DISPLAY INVISIBLE (-6425 2750);
FORCEPROP 1 LAST PATH I7
J 0
(-6375 2825);
DISPLAY 0.872340 (-6375 2825);
PAINT AQUA (-6375 2825);
DISPLAY INVISIBLE (-6375 2825);
FORCEADD Q_CAP..1
(-1525 4325);
FORCEPROP 1 LAST LOCATION C429
J 0
(-1475 4425);
DISPLAY 0.978723 (-1475 4425);
PAINT WHITE (-1475 4425);
FORCEPROP 0 LAST $SEC 1
J 0
(-1475 4475);
DISPLAY 0.680851 (-1475 4475);
PAINT MONO (-1475 4475);
DISPLAY INVISIBLE (-1475 4475);
FORCEPROP 0 LAST CDS_SEC 1
J 0
(-1475 4475);
DISPLAY 0.680851 (-1475 4475);
DISPLAY INVISIBLE (-1475 4475);
FORCEPROP 1 LASTPIN (-1525 4425) $PN 1
J 0
(-1515 4405);
DISPLAY 0.787234 (-1515 4405);
PAINT MONO (-1515 4405);
FORCEPROP 1 LASTPIN (-1525 4225) $PN 2
J 0
(-1515 4205);
DISPLAY 0.787234 (-1515 4205);
PAINT MONO (-1515 4205);
FORCEPROP 1 LAST VOLTAGE 6.3V
J 0
(-1475 4325);
DISPLAY 0.510638 (-1475 4325);
FORCEPROP 1 LAST VALUE 10UF
J 0
(-1475 4375);
DISPLAY 0.510638 (-1475 4375);
FORCEPROP 1 LAST MATERIAL X6S
J 0
(-1475 4225);
DISPLAY 0.510638 (-1475 4225);
FORCEPROP 1 LAST TOLERANCE 20%
J 0
(-1475 4275);
DISPLAY 0.510638 (-1475 4275);
FORCEPROP 1 LAST PACK_TYPE C0402
J 0
(-1475 4175);
DISPLAY 0.510638 (-1475 4175);
FORCEPROP 2 LAST CDS_LIB pure_quanta
J 0
(-1525 4325);
DISPLAY INVISIBLE (-1525 4325);
FORCEPROP 1 LAST PATH I70
J 0
(-1475 4475);
DISPLAY 0.978723 (-1475 4475);
PAINT WHITE (-1475 4475);
DISPLAY INVISIBLE (-1475 4475);
FORCEPROP 1 LAST PART_NUMBER CH6101MEB01
J 0
(-1475 4175);
DISPLAY 0.978723 (-1475 4175);
DISPLAY INVISIBLE (-1475 4175);
FORCEADD Q_CAP..1
(-1350 3700);
FORCEPROP 1 LAST LOCATION C382
J 0
(-1300 3800);
DISPLAY 0.978723 (-1300 3800);
PAINT WHITE (-1300 3800);
FORCEPROP 0 LAST $SEC 1
J 0
(-1300 3850);
DISPLAY 0.680851 (-1300 3850);
PAINT MONO (-1300 3850);
DISPLAY INVISIBLE (-1300 3850);
FORCEPROP 0 LAST CDS_SEC 1
J 0
(-1300 3850);
DISPLAY 0.680851 (-1300 3850);
DISPLAY INVISIBLE (-1300 3850);
FORCEPROP 1 LASTPIN (-1350 3800) $PN 1
J 0
(-1340 3780);
DISPLAY 0.787234 (-1340 3780);
PAINT MONO (-1340 3780);
FORCEPROP 1 LASTPIN (-1350 3600) $PN 2
J 0
(-1340 3580);
DISPLAY 0.787234 (-1340 3580);
PAINT MONO (-1340 3580);
FORCEPROP 1 LAST TOLERANCE 20%
J 0
(-1300 3650);
DISPLAY 0.510638 (-1300 3650);
FORCEPROP 1 LAST PACK_TYPE 0201
J 0
(-1300 3550);
DISPLAY 0.510638 (-1300 3550);
FORCEPROP 1 LAST VOLTAGE 4V
J 0
(-1300 3700);
DISPLAY 0.510638 (-1300 3700);
FORCEPROP 1 LAST VALUE 1UF
J 0
(-1300 3750);
DISPLAY 0.510638 (-1300 3750);
FORCEPROP 1 LAST MATERIAL X6S
J 0
(-1300 3600);
DISPLAY 0.510638 (-1300 3600);
FORCEPROP 2 LAST CDS_LIB pure_quanta
J 0
(-1350 3700);
DISPLAY INVISIBLE (-1350 3700);
FORCEPROP 1 LAST PATH I71
J 0
(-1300 3850);
DISPLAY 0.978723 (-1300 3850);
PAINT WHITE (-1300 3850);
DISPLAY INVISIBLE (-1300 3850);
FORCEPROP 1 LAST PART_NUMBER CH-10KMEE00
J 0
(-1300 3550);
DISPLAY 0.510638 (-1300 3550);
DISPLAY INVISIBLE (-1300 3550);
FORCEADD Q_CAP..1
(-1225 4325);
FORCEPROP 1 LAST LOCATION C431
J 0
(-1175 4425);
DISPLAY 0.978723 (-1175 4425);
PAINT WHITE (-1175 4425);
FORCEPROP 0 LAST $SEC 1
J 0
(-1175 4475);
DISPLAY 0.680851 (-1175 4475);
PAINT MONO (-1175 4475);
DISPLAY INVISIBLE (-1175 4475);
FORCEPROP 0 LAST CDS_SEC 1
J 0
(-1175 4475);
DISPLAY 0.680851 (-1175 4475);
DISPLAY INVISIBLE (-1175 4475);
FORCEPROP 1 LASTPIN (-1225 4425) $PN 1
J 0
(-1215 4405);
DISPLAY 0.787234 (-1215 4405);
PAINT MONO (-1215 4405);
FORCEPROP 1 LASTPIN (-1225 4225) $PN 2
J 0
(-1215 4205);
DISPLAY 0.787234 (-1215 4205);
PAINT MONO (-1215 4205);
FORCEPROP 1 LAST VALUE 10UF
J 0
(-1175 4375);
DISPLAY 0.510638 (-1175 4375);
FORCEPROP 1 LAST VOLTAGE 6.3V
J 0
(-1175 4325);
DISPLAY 0.510638 (-1175 4325);
FORCEPROP 1 LAST TOLERANCE 20%
J 0
(-1175 4275);
DISPLAY 0.510638 (-1175 4275);
FORCEPROP 1 LAST MATERIAL X6S
J 0
(-1175 4225);
DISPLAY 0.510638 (-1175 4225);
FORCEPROP 1 LAST PACK_TYPE C0402
J 0
(-1175 4175);
DISPLAY 0.510638 (-1175 4175);
FORCEPROP 2 LAST CDS_LIB pure_quanta
J 0
(-1225 4325);
DISPLAY INVISIBLE (-1225 4325);
FORCEPROP 1 LAST PATH I72
J 0
(-1175 4475);
DISPLAY 0.978723 (-1175 4475);
PAINT WHITE (-1175 4475);
DISPLAY INVISIBLE (-1175 4475);
FORCEPROP 1 LAST PART_NUMBER CH6101MEB01
J 0
(-1175 4175);
DISPLAY 0.978723 (-1175 4175);
DISPLAY INVISIBLE (-1175 4175);
FORCEADD UNIVERSAL_GND..1
(-825 2650);
FORCEPROP 3 LASTPIN (-825 2700) SIG_NAME GND\g
J 0
(-815 2710);
DISPLAY 0.659574 (-815 2710);
PAINT MONO (-815 2710);
DISPLAY INVISIBLE (-815 2710);
FORCEPROP 2 LAST CDS_LIB pure_quanta_power
J 0
(-825 2650);
DISPLAY INVISIBLE (-825 2650);
FORCEPROP 1 LAST HDL_POWER GND
J 1
(-800 2575);
DISPLAY 0.872340 (-800 2575);
PAINT GREEN (-800 2575);
DISPLAY INVISIBLE (-800 2575);
FORCEPROP 1 LAST PATH I73
J 0
(-750 2650);
DISPLAY 0.872340 (-750 2650);
PAINT AQUA (-750 2650);
DISPLAY INVISIBLE (-750 2650);
FORCEADD Q_INDUCTOR..1
(-3775 4600);
FORCEPROP 1 LAST LOCATION L8
J 0
(-3900 4760);
DISPLAY 0.723404 (-3900 4760);
PAINT GREEN (-3900 4760);
FORCEPROP 0 LAST $SEC 1
J 0
(-3900 4900);
DISPLAY 0.680851 (-3900 4900);
PAINT MONO (-3900 4900);
DISPLAY INVISIBLE (-3900 4900);
FORCEPROP 0 LAST CDS_SEC 1
J 0
(-3900 4900);
DISPLAY 0.680851 (-3900 4900);
DISPLAY INVISIBLE (-3900 4900);
FORCEPROP 0 LASTPIN (-3875 4575) $PN 1
J 2
(-3885 4585);
DISPLAY 0.680851 (-3885 4585);
PAINT MONO (-3885 4585);
FORCEPROP 0 LASTPIN (-3675 4575) $PN 2
J 0
(-3665 4585);
DISPLAY 0.680851 (-3665 4585);
PAINT MONO (-3665 4585);
FORCEPROP 1 LAST MATERIAL IND
J 0
(-3900 4655);
DISPLAY 0.723404 (-3900 4655);
PAINT GREEN (-3900 4655);
FORCEPROP 2 LAST PACK_TYPE SMLF
J 0
(-3900 4800);
DISPLAY 0.680851 (-3900 4800);
FORCEPROP 2 LAST VALUE 100NH/16A
J 0
(-3900 4850);
DISPLAY 0.680851 (-3900 4850);
FORCEPROP 2 LAST CDS_LIB pure_quanta
J 0
(-3775 4600);
DISPLAY INVISIBLE (-3775 4600);
FORCEPROP 1 LAST NEEDS_NO_SIZE TRUE
J 0
(-3775 4600);
DISPLAY 0.468085 (-3775 4600);
PAINT GREEN (-3775 4600);
DISPLAY INVISIBLE (-3775 4600);
FORCEPROP 1 LAST PATH I74
J 0
(-3700 4655);
DISPLAY 0.723404 (-3700 4655);
PAINT GREEN (-3700 4655);
DISPLAY INVISIBLE (-3700 4655);
FORCEPROP 1 LAST PART_NUMBER CV+10G0MZ04
J 0
(-3900 4710);
DISPLAY 0.723404 (-3900 4710);
PAINT GREEN (-3900 4710);
DISPLAY INVISIBLE (-3900 4710);
FORCEADD VCC_CORE..1
(-3425 4975);
FORCEPROP 3 LASTPIN (-3425 4925) SIG_NAME P0V9_CPU1_RT2_2A\g
J 0
(-3415 4935);
DISPLAY 0.659574 (-3415 4935);
PAINT MONO (-3415 4935);
DISPLAY INVISIBLE (-3415 4935);
FORCEPROP 1 LAST HDL_POWER P0V9_CPU1_RT2_2A
J 1
(-3425 5025);
DISPLAY 0.617021 (-3425 5025);
PAINT GREEN (-3425 5025);
FORCEPROP 2 LAST CDS_LIB pure_quanta_power
J 0
(-3425 4975);
DISPLAY INVISIBLE (-3425 4975);
FORCEPROP 1 LAST PATH I75
J 0
(-3375 5000);
DISPLAY 0.872340 (-3375 5000);
PAINT AQUA (-3375 5000);
DISPLAY INVISIBLE (-3375 5000);
FORCEADD Q_CAP..1
(-4100 5625);
FORCEPROP 1 LAST LOCATION C404
J 0
(-4050 5725);
DISPLAY 0.978723 (-4050 5725);
PAINT WHITE (-4050 5725);
FORCEPROP 0 LAST $SEC 1
J 0
(-4050 5775);
DISPLAY 0.680851 (-4050 5775);
PAINT MONO (-4050 5775);
DISPLAY INVISIBLE (-4050 5775);
FORCEPROP 0 LAST CDS_SEC 1
J 0
(-4050 5775);
DISPLAY 0.680851 (-4050 5775);
DISPLAY INVISIBLE (-4050 5775);
FORCEPROP 1 LASTPIN (-4100 5725) $PN 1
J 0
(-4090 5705);
DISPLAY 0.787234 (-4090 5705);
PAINT MONO (-4090 5705);
FORCEPROP 1 LASTPIN (-4100 5525) $PN 2
J 0
(-4090 5505);
DISPLAY 0.787234 (-4090 5505);
PAINT MONO (-4090 5505);
FORCEPROP 1 LAST PACK_TYPE C0805
J 0
(-4050 5475);
DISPLAY 0.510638 (-4050 5475);
FORCEPROP 1 LAST VOLTAGE 4V
J 0
(-4050 5625);
DISPLAY 0.510638 (-4050 5625);
FORCEPROP 1 LAST VALUE 100UF
J 0
(-4050 5675);
DISPLAY 0.510638 (-4050 5675);
FORCEPROP 1 LAST TOLERANCE 20%
J 0
(-4050 5575);
DISPLAY 0.510638 (-4050 5575);
FORCEPROP 1 LAST MATERIAL X6S
J 0
(-4050 5525);
DISPLAY 0.510638 (-4050 5525);
FORCEPROP 2 LAST CDS_LIB pure_quanta
J 0
(-4100 5625);
DISPLAY INVISIBLE (-4100 5625);
FORCEPROP 1 LAST PATH I76
J 0
(-4050 5775);
DISPLAY 0.978723 (-4050 5775);
PAINT WHITE (-4050 5775);
DISPLAY INVISIBLE (-4050 5775);
FORCEPROP 1 LAST PART_NUMBER CH710KMEA01
J 0
(-4050 5475);
DISPLAY 0.404255 (-4050 5475);
DISPLAY INVISIBLE (-4050 5475);
FORCEADD Q_CAP..1
(-3825 5625);
FORCEPROP 1 LAST LOCATION C408
J 0
(-3775 5725);
DISPLAY 0.978723 (-3775 5725);
PAINT WHITE (-3775 5725);
FORCEPROP 0 LAST $SEC 1
J 0
(-3775 5775);
DISPLAY 0.680851 (-3775 5775);
PAINT MONO (-3775 5775);
DISPLAY INVISIBLE (-3775 5775);
FORCEPROP 0 LAST CDS_SEC 1
J 0
(-3775 5775);
DISPLAY 0.680851 (-3775 5775);
DISPLAY INVISIBLE (-3775 5775);
FORCEPROP 1 LASTPIN (-3825 5725) $PN 1
J 0
(-3815 5705);
DISPLAY 0.787234 (-3815 5705);
PAINT MONO (-3815 5705);
FORCEPROP 1 LASTPIN (-3825 5525) $PN 2
J 0
(-3815 5505);
DISPLAY 0.787234 (-3815 5505);
PAINT MONO (-3815 5505);
FORCEPROP 1 LAST VOLTAGE 4V
J 0
(-3775 5625);
DISPLAY 0.510638 (-3775 5625);
FORCEPROP 1 LAST TOLERANCE 20%
J 0
(-3775 5575);
DISPLAY 0.510638 (-3775 5575);
FORCEPROP 1 LAST VALUE 22UF
J 0
(-3775 5675);
DISPLAY 0.510638 (-3775 5675);
FORCEPROP 1 LAST MATERIAL X6S
J 0
(-3775 5525);
DISPLAY 0.510638 (-3775 5525);
FORCEPROP 1 LAST PACK_TYPE C0402
J 0
(-3775 5475);
DISPLAY 0.510638 (-3775 5475);
FORCEPROP 2 LAST CDS_LIB pure_quanta
J 0
(-3825 5625);
DISPLAY INVISIBLE (-3825 5625);
FORCEPROP 1 LAST PATH I77
J 0
(-3775 5775);
DISPLAY 0.978723 (-3775 5775);
PAINT WHITE (-3775 5775);
DISPLAY INVISIBLE (-3775 5775);
FORCEPROP 1 LAST PART_NUMBER CH622KMEB02
J 0
(-3775 5475);
DISPLAY 0.978723 (-3775 5475);
DISPLAY INVISIBLE (-3775 5475);
FORCEADD Q_CAP..1
(-3500 5600);
FORCEPROP 1 LAST LOCATION C414
J 0
(-3450 5700);
DISPLAY 0.978723 (-3450 5700);
PAINT WHITE (-3450 5700);
FORCEPROP 0 LAST $SEC 1
J 0
(-3450 5750);
DISPLAY 0.680851 (-3450 5750);
PAINT MONO (-3450 5750);
DISPLAY INVISIBLE (-3450 5750);
FORCEPROP 0 LAST CDS_SEC 1
J 0
(-3450 5750);
DISPLAY 0.680851 (-3450 5750);
DISPLAY INVISIBLE (-3450 5750);
FORCEPROP 1 LASTPIN (-3500 5700) $PN 1
J 0
(-3490 5680);
DISPLAY 0.787234 (-3490 5680);
PAINT MONO (-3490 5680);
FORCEPROP 1 LASTPIN (-3500 5500) $PN 2
J 0
(-3490 5480);
DISPLAY 0.787234 (-3490 5480);
PAINT MONO (-3490 5480);
FORCEPROP 1 LAST VOLTAGE 6.3V
J 0
(-3450 5600);
DISPLAY 0.510638 (-3450 5600);
FORCEPROP 1 LAST VALUE 10UF
J 0
(-3450 5650);
DISPLAY 0.510638 (-3450 5650);
FORCEPROP 1 LAST PACK_TYPE C0402
J 0
(-3450 5450);
DISPLAY 0.510638 (-3450 5450);
FORCEPROP 1 LAST MATERIAL X6S
J 0
(-3450 5500);
DISPLAY 0.510638 (-3450 5500);
FORCEPROP 1 LAST TOLERANCE 20%
J 0
(-3450 5550);
DISPLAY 0.510638 (-3450 5550);
FORCEPROP 2 LAST CDS_LIB pure_quanta
J 0
(-3500 5600);
DISPLAY INVISIBLE (-3500 5600);
FORCEPROP 1 LAST PATH I78
J 0
(-3450 5750);
DISPLAY 0.978723 (-3450 5750);
PAINT WHITE (-3450 5750);
DISPLAY INVISIBLE (-3450 5750);
FORCEPROP 1 LAST PART_NUMBER CH6101MEB01
J 0
(-3450 5450);
DISPLAY 0.978723 (-3450 5450);
DISPLAY INVISIBLE (-3450 5450);
FORCEADD Q_CAP..1
(-3200 5600);
FORCEPROP 1 LAST LOCATION C419
J 0
(-3150 5700);
DISPLAY 0.978723 (-3150 5700);
PAINT WHITE (-3150 5700);
FORCEPROP 0 LAST $SEC 1
J 0
(-3150 5750);
DISPLAY 0.680851 (-3150 5750);
PAINT MONO (-3150 5750);
DISPLAY INVISIBLE (-3150 5750);
FORCEPROP 0 LAST CDS_SEC 1
J 0
(-3150 5750);
DISPLAY 0.680851 (-3150 5750);
DISPLAY INVISIBLE (-3150 5750);
FORCEPROP 1 LASTPIN (-3200 5700) $PN 1
J 0
(-3190 5680);
DISPLAY 0.787234 (-3190 5680);
PAINT MONO (-3190 5680);
FORCEPROP 1 LASTPIN (-3200 5500) $PN 2
J 0
(-3190 5480);
DISPLAY 0.787234 (-3190 5480);
PAINT MONO (-3190 5480);
FORCEPROP 1 LAST VALUE 4.7UF
J 0
(-3150 5650);
DISPLAY 0.510638 (-3150 5650);
FORCEPROP 1 LAST VOLTAGE 6.3V
J 0
(-3150 5600);
DISPLAY 0.510638 (-3150 5600);
FORCEPROP 1 LAST TOLERANCE 20%
J 0
(-3150 5550);
DISPLAY 0.510638 (-3150 5550);
FORCEPROP 1 LAST MATERIAL X6S
J 0
(-3150 5500);
DISPLAY 0.510638 (-3150 5500);
FORCEPROP 1 LAST PACK_TYPE 0402
J 0
(-3150 5450);
DISPLAY 0.510638 (-3150 5450);
FORCEPROP 2 LAST CDS_LIB pure_quanta
J 0
(-3200 5600);
DISPLAY INVISIBLE (-3200 5600);
FORCEPROP 1 LAST PATH I79
J 0
(-3150 5750);
DISPLAY 0.978723 (-3150 5750);
PAINT WHITE (-3150 5750);
DISPLAY INVISIBLE (-3150 5750);
FORCEPROP 1 LAST PART_NUMBER CH5471MEB01
J 0
(-3150 5450);
DISPLAY 0.978723 (-3150 5450);
DISPLAY INVISIBLE (-3150 5450);
FORCEADD Q_CAP..1
(-6450 3225);
FORCEPROP 1 LAST LOCATION C378
J 0
(-6400 3325);
DISPLAY 0.978723 (-6400 3325);
PAINT WHITE (-6400 3325);
FORCEPROP 0 LAST $SEC 1
J 0
(-6400 3375);
DISPLAY 0.680851 (-6400 3375);
PAINT MONO (-6400 3375);
DISPLAY INVISIBLE (-6400 3375);
FORCEPROP 0 LAST CDS_SEC 1
J 0
(-6400 3375);
DISPLAY 0.680851 (-6400 3375);
DISPLAY INVISIBLE (-6400 3375);
FORCEPROP 1 LASTPIN (-6450 3325) $PN 1
J 0
(-6440 3305);
DISPLAY 0.787234 (-6440 3305);
PAINT MONO (-6440 3305);
FORCEPROP 1 LASTPIN (-6450 3125) $PN 2
J 0
(-6440 3105);
DISPLAY 0.787234 (-6440 3105);
PAINT MONO (-6440 3105);
FORCEPROP 1 LAST TOLERANCE 10%
J 0
(-6400 3175);
DISPLAY 0.638298 (-6400 3175);
FORCEPROP 1 LAST VALUE 0.1UF
J 0
(-6400 3275);
DISPLAY 0.638298 (-6400 3275);
FORCEPROP 1 LAST VOLTAGE 10V
J 0
(-6400 3225);
DISPLAY 0.638298 (-6400 3225);
FORCEPROP 1 LAST MATERIAL X7S
J 0
(-6400 3125);
DISPLAY 0.638298 (-6400 3125);
FORCEPROP 1 LAST PACK_TYPE C0201
J 0
(-6400 3075);
DISPLAY 0.638298 (-6400 3075);
FORCEPROP 2 LAST CDS_LIB pure_quanta
J 0
(-6450 3225);
DISPLAY INVISIBLE (-6450 3225);
FORCEPROP 1 LAST PATH I8
J 0
(-6400 3375);
DISPLAY 0.978723 (-6400 3375);
PAINT WHITE (-6400 3375);
DISPLAY INVISIBLE (-6400 3375);
FORCEPROP 1 LAST PART_NUMBER CH4102K6E00
J 0
(-6400 3075);
DISPLAY 0.978723 (-6400 3075);
DISPLAY INVISIBLE (-6400 3075);
FORCEADD Q_CAP..1
(-2900 5600);
FORCEPROP 1 LAST LOCATION C423
J 0
(-2850 5700);
DISPLAY 0.978723 (-2850 5700);
PAINT WHITE (-2850 5700);
FORCEPROP 0 LAST $SEC 1
J 0
(-2850 5750);
DISPLAY 0.680851 (-2850 5750);
PAINT MONO (-2850 5750);
DISPLAY INVISIBLE (-2850 5750);
FORCEPROP 0 LAST CDS_SEC 1
J 0
(-2850 5750);
DISPLAY 0.680851 (-2850 5750);
DISPLAY INVISIBLE (-2850 5750);
FORCEPROP 1 LASTPIN (-2900 5700) $PN 1
J 0
(-2890 5680);
DISPLAY 0.787234 (-2890 5680);
PAINT MONO (-2890 5680);
FORCEPROP 1 LASTPIN (-2900 5500) $PN 2
J 0
(-2890 5480);
DISPLAY 0.787234 (-2890 5480);
PAINT MONO (-2890 5480);
FORCEPROP 1 LAST VALUE 1UF
J 0
(-2850 5650);
DISPLAY 0.510638 (-2850 5650);
FORCEPROP 1 LAST VOLTAGE 4V
J 0
(-2850 5600);
DISPLAY 0.510638 (-2850 5600);
FORCEPROP 1 LAST TOLERANCE 20%
J 0
(-2850 5550);
DISPLAY 0.510638 (-2850 5550);
FORCEPROP 1 LAST PACK_TYPE 0201
J 0
(-2850 5450);
DISPLAY 0.510638 (-2850 5450);
FORCEPROP 1 LAST MATERIAL X6S
J 0
(-2850 5500);
DISPLAY 0.510638 (-2850 5500);
FORCEPROP 2 LAST CDS_LIB pure_quanta
J 0
(-2900 5600);
DISPLAY INVISIBLE (-2900 5600);
FORCEPROP 1 LAST PATH I80
J 0
(-2850 5750);
DISPLAY 0.978723 (-2850 5750);
PAINT WHITE (-2850 5750);
DISPLAY INVISIBLE (-2850 5750);
FORCEPROP 1 LAST PART_NUMBER CH-10KMEE00
J 0
(-2850 5450);
DISPLAY 0.510638 (-2850 5450);
DISPLAY INVISIBLE (-2850 5450);
FORCEADD UNIVERSAL_GND..1
(-225 4600);
FORCEPROP 3 LASTPIN (-225 4650) SIG_NAME GND\g
J 0
(-215 4660);
DISPLAY 0.659574 (-215 4660);
PAINT MONO (-215 4660);
DISPLAY INVISIBLE (-215 4660);
FORCEPROP 2 LAST CDS_LIB pure_quanta_power
J 0
(-225 4600);
DISPLAY INVISIBLE (-225 4600);
FORCEPROP 1 LAST HDL_POWER GND
J 1
(-200 4525);
DISPLAY 0.872340 (-200 4525);
PAINT GREEN (-200 4525);
DISPLAY INVISIBLE (-200 4525);
FORCEPROP 1 LAST PATH I81
J 0
(-150 4600);
DISPLAY 0.872340 (-150 4600);
PAINT AQUA (-150 4600);
DISPLAY INVISIBLE (-150 4600);
FORCEADD Q_CAP..1
(-2600 5575);
FORCEPROP 1 LAST LOCATION C383
J 0
(-2550 5675);
DISPLAY 0.978723 (-2550 5675);
PAINT WHITE (-2550 5675);
FORCEPROP 0 LAST $SEC 1
J 0
(-2550 5725);
DISPLAY 0.680851 (-2550 5725);
PAINT MONO (-2550 5725);
DISPLAY INVISIBLE (-2550 5725);
FORCEPROP 0 LAST CDS_SEC 1
J 0
(-2550 5725);
DISPLAY 0.680851 (-2550 5725);
DISPLAY INVISIBLE (-2550 5725);
FORCEPROP 1 LASTPIN (-2600 5675) $PN 1
J 0
(-2590 5655);
DISPLAY 0.787234 (-2590 5655);
PAINT MONO (-2590 5655);
FORCEPROP 1 LASTPIN (-2600 5475) $PN 2
J 0
(-2590 5455);
DISPLAY 0.787234 (-2590 5455);
PAINT MONO (-2590 5455);
FORCEPROP 1 LAST PACK_TYPE C0201
J 0
(-2550 5425);
DISPLAY 0.638298 (-2550 5425);
FORCEPROP 1 LAST VOLTAGE 10V
J 0
(-2550 5575);
DISPLAY 0.638298 (-2550 5575);
FORCEPROP 1 LAST VALUE 0.1UF
J 0
(-2550 5625);
DISPLAY 0.638298 (-2550 5625);
FORCEPROP 1 LAST MATERIAL X7S
J 0
(-2550 5475);
DISPLAY 0.638298 (-2550 5475);
FORCEPROP 1 LAST TOLERANCE 10%
J 0
(-2550 5525);
DISPLAY 0.638298 (-2550 5525);
FORCEPROP 2 LAST CDS_LIB pure_quanta
J 0
(-2600 5575);
DISPLAY INVISIBLE (-2600 5575);
FORCEPROP 1 LAST PATH I82
J 0
(-2550 5725);
DISPLAY 0.978723 (-2550 5725);
PAINT WHITE (-2550 5725);
DISPLAY INVISIBLE (-2550 5725);
FORCEPROP 1 LAST PART_NUMBER CH4102K6E00
J 0
(-2550 5425);
DISPLAY 0.978723 (-2550 5425);
DISPLAY INVISIBLE (-2550 5425);
FORCEADD Q_CAP..1
(-2325 5575);
FORCEPROP 1 LAST LOCATION C385
J 0
(-2275 5675);
DISPLAY 0.978723 (-2275 5675);
PAINT WHITE (-2275 5675);
FORCEPROP 0 LAST $SEC 1
J 0
(-2275 5725);
DISPLAY 0.680851 (-2275 5725);
PAINT MONO (-2275 5725);
DISPLAY INVISIBLE (-2275 5725);
FORCEPROP 0 LAST CDS_SEC 1
J 0
(-2275 5725);
DISPLAY 0.680851 (-2275 5725);
DISPLAY INVISIBLE (-2275 5725);
FORCEPROP 1 LASTPIN (-2325 5675) $PN 1
J 0
(-2315 5655);
DISPLAY 0.787234 (-2315 5655);
PAINT MONO (-2315 5655);
FORCEPROP 1 LASTPIN (-2325 5475) $PN 2
J 0
(-2315 5455);
DISPLAY 0.787234 (-2315 5455);
PAINT MONO (-2315 5455);
FORCEPROP 1 LAST PACK_TYPE C0201
J 0
(-2275 5425);
DISPLAY 0.638298 (-2275 5425);
FORCEPROP 1 LAST MATERIAL X7S
J 0
(-2275 5475);
DISPLAY 0.638298 (-2275 5475);
FORCEPROP 1 LAST VALUE 0.1UF
J 0
(-2275 5625);
DISPLAY 0.638298 (-2275 5625);
FORCEPROP 1 LAST VOLTAGE 10V
J 0
(-2275 5575);
DISPLAY 0.638298 (-2275 5575);
FORCEPROP 1 LAST TOLERANCE 10%
J 0
(-2275 5525);
DISPLAY 0.638298 (-2275 5525);
FORCEPROP 2 LAST CDS_LIB pure_quanta
J 0
(-2325 5575);
DISPLAY INVISIBLE (-2325 5575);
FORCEPROP 1 LAST PATH I83
J 0
(-2275 5725);
DISPLAY 0.978723 (-2275 5725);
PAINT WHITE (-2275 5725);
DISPLAY INVISIBLE (-2275 5725);
FORCEPROP 1 LAST PART_NUMBER CH4102K6E00
J 0
(-2275 5425);
DISPLAY 0.978723 (-2275 5425);
DISPLAY INVISIBLE (-2275 5425);
FORCEADD Q_CAP..1
(-2075 5575);
FORCEPROP 1 LAST LOCATION C388
J 0
(-2025 5675);
DISPLAY 0.978723 (-2025 5675);
PAINT WHITE (-2025 5675);
FORCEPROP 0 LAST $SEC 1
J 0
(-2025 5725);
DISPLAY 0.680851 (-2025 5725);
PAINT MONO (-2025 5725);
DISPLAY INVISIBLE (-2025 5725);
FORCEPROP 0 LAST CDS_SEC 1
J 0
(-2025 5725);
DISPLAY 0.680851 (-2025 5725);
DISPLAY INVISIBLE (-2025 5725);
FORCEPROP 1 LASTPIN (-2075 5675) $PN 1
J 0
(-2065 5655);
DISPLAY 0.787234 (-2065 5655);
PAINT MONO (-2065 5655);
FORCEPROP 1 LASTPIN (-2075 5475) $PN 2
J 0
(-2065 5455);
DISPLAY 0.787234 (-2065 5455);
PAINT MONO (-2065 5455);
FORCEPROP 1 LAST VALUE 0.1UF
J 0
(-2025 5625);
DISPLAY 0.638298 (-2025 5625);
FORCEPROP 1 LAST VOLTAGE 10V
J 0
(-2025 5575);
DISPLAY 0.638298 (-2025 5575);
FORCEPROP 1 LAST TOLERANCE 10%
J 0
(-2025 5525);
DISPLAY 0.638298 (-2025 5525);
FORCEPROP 1 LAST MATERIAL X7S
J 0
(-2025 5475);
DISPLAY 0.638298 (-2025 5475);
FORCEPROP 1 LAST PACK_TYPE C0201
J 0
(-2025 5425);
DISPLAY 0.638298 (-2025 5425);
FORCEPROP 2 LAST CDS_LIB pure_quanta
J 0
(-2075 5575);
DISPLAY INVISIBLE (-2075 5575);
FORCEPROP 1 LAST PATH I84
J 0
(-2025 5725);
DISPLAY 0.978723 (-2025 5725);
PAINT WHITE (-2025 5725);
DISPLAY INVISIBLE (-2025 5725);
FORCEPROP 1 LAST PART_NUMBER CH4102K6E00
J 0
(-2025 5425);
DISPLAY 0.978723 (-2025 5425);
DISPLAY INVISIBLE (-2025 5425);
FORCEADD Q_CAP..1
(-1800 5575);
FORCEPROP 1 LAST LOCATION C392
J 0
(-1750 5675);
DISPLAY 0.978723 (-1750 5675);
PAINT WHITE (-1750 5675);
FORCEPROP 0 LAST $SEC 1
J 0
(-1750 5725);
DISPLAY 0.680851 (-1750 5725);
PAINT MONO (-1750 5725);
DISPLAY INVISIBLE (-1750 5725);
FORCEPROP 0 LAST CDS_SEC 1
J 0
(-1750 5725);
DISPLAY 0.680851 (-1750 5725);
DISPLAY INVISIBLE (-1750 5725);
FORCEPROP 1 LASTPIN (-1800 5675) $PN 1
J 0
(-1790 5655);
DISPLAY 0.787234 (-1790 5655);
PAINT MONO (-1790 5655);
FORCEPROP 1 LASTPIN (-1800 5475) $PN 2
J 0
(-1790 5455);
DISPLAY 0.787234 (-1790 5455);
PAINT MONO (-1790 5455);
FORCEPROP 1 LAST VALUE 0.1UF
J 0
(-1750 5625);
DISPLAY 0.638298 (-1750 5625);
FORCEPROP 1 LAST MATERIAL X7S
J 0
(-1750 5475);
DISPLAY 0.638298 (-1750 5475);
FORCEPROP 1 LAST TOLERANCE 10%
J 0
(-1750 5525);
DISPLAY 0.638298 (-1750 5525);
FORCEPROP 1 LAST VOLTAGE 10V
J 0
(-1750 5575);
DISPLAY 0.638298 (-1750 5575);
FORCEPROP 1 LAST PACK_TYPE C0201
J 0
(-1750 5425);
DISPLAY 0.638298 (-1750 5425);
FORCEPROP 2 LAST CDS_LIB pure_quanta
J 0
(-1800 5575);
DISPLAY INVISIBLE (-1800 5575);
FORCEPROP 1 LAST PATH I85
J 0
(-1750 5725);
DISPLAY 0.978723 (-1750 5725);
PAINT WHITE (-1750 5725);
DISPLAY INVISIBLE (-1750 5725);
FORCEPROP 1 LAST PART_NUMBER CH4102K6E00
J 0
(-1750 5425);
DISPLAY 0.978723 (-1750 5425);
DISPLAY INVISIBLE (-1750 5425);
FORCEADD Q_CAP..1
(-2975 4325);
FORCEPROP 1 LAST LOCATION C405
J 0
(-2925 4425);
DISPLAY 0.978723 (-2925 4425);
PAINT WHITE (-2925 4425);
FORCEPROP 0 LAST $SEC 1
J 0
(-2925 4475);
DISPLAY 0.680851 (-2925 4475);
PAINT MONO (-2925 4475);
DISPLAY INVISIBLE (-2925 4475);
FORCEPROP 0 LAST CDS_SEC 1
J 0
(-2925 4475);
DISPLAY 0.680851 (-2925 4475);
DISPLAY INVISIBLE (-2925 4475);
FORCEPROP 1 LASTPIN (-2975 4425) $PN 1
J 0
(-2965 4405);
DISPLAY 0.787234 (-2965 4405);
PAINT MONO (-2965 4405);
FORCEPROP 1 LASTPIN (-2975 4225) $PN 2
J 0
(-2965 4205);
DISPLAY 0.787234 (-2965 4205);
PAINT MONO (-2965 4205);
FORCEPROP 1 LAST VALUE 100UF
J 0
(-2925 4375);
DISPLAY 0.510638 (-2925 4375);
FORCEPROP 1 LAST PACK_TYPE C0805
J 0
(-2925 4175);
DISPLAY 0.510638 (-2925 4175);
FORCEPROP 1 LAST MATERIAL X6S
J 0
(-2925 4225);
DISPLAY 0.510638 (-2925 4225);
FORCEPROP 1 LAST TOLERANCE 20%
J 0
(-2925 4275);
DISPLAY 0.510638 (-2925 4275);
FORCEPROP 1 LAST VOLTAGE 4V
J 0
(-2925 4325);
DISPLAY 0.510638 (-2925 4325);
FORCEPROP 2 LAST CDS_LIB pure_quanta
J 0
(-2975 4325);
DISPLAY INVISIBLE (-2975 4325);
FORCEPROP 1 LAST PATH I86
J 0
(-2925 4475);
DISPLAY 0.978723 (-2925 4475);
PAINT WHITE (-2925 4475);
DISPLAY INVISIBLE (-2925 4475);
FORCEPROP 1 LAST PART_NUMBER CH710KMEA01
J 0
(-2925 4175);
DISPLAY 0.404255 (-2925 4175);
DISPLAY INVISIBLE (-2925 4175);
FORCEADD Q_CAP..1
(-2750 4325);
FORCEPROP 1 LAST LOCATION C409
J 0
(-2700 4425);
DISPLAY 0.978723 (-2700 4425);
PAINT WHITE (-2700 4425);
FORCEPROP 0 LAST $SEC 1
J 0
(-2700 4475);
DISPLAY 0.680851 (-2700 4475);
PAINT MONO (-2700 4475);
DISPLAY INVISIBLE (-2700 4475);
FORCEPROP 0 LAST CDS_SEC 1
J 0
(-2700 4475);
DISPLAY 0.680851 (-2700 4475);
DISPLAY INVISIBLE (-2700 4475);
FORCEPROP 1 LASTPIN (-2750 4425) $PN 1
J 0
(-2740 4405);
DISPLAY 0.787234 (-2740 4405);
PAINT MONO (-2740 4405);
FORCEPROP 1 LASTPIN (-2750 4225) $PN 2
J 0
(-2740 4205);
DISPLAY 0.787234 (-2740 4205);
PAINT MONO (-2740 4205);
FORCEPROP 1 LAST TOLERANCE 20%
J 0
(-2700 4275);
DISPLAY 0.510638 (-2700 4275);
FORCEPROP 1 LAST PACK_TYPE C0805
J 0
(-2700 4175);
DISPLAY 0.510638 (-2700 4175);
FORCEPROP 1 LAST VALUE 100UF
J 0
(-2700 4375);
DISPLAY 0.510638 (-2700 4375);
FORCEPROP 1 LAST VOLTAGE 4V
J 0
(-2700 4325);
DISPLAY 0.510638 (-2700 4325);
FORCEPROP 1 LAST MATERIAL X6S
J 0
(-2700 4225);
DISPLAY 0.510638 (-2700 4225);
FORCEPROP 2 LAST CDS_LIB pure_quanta
J 0
(-2750 4325);
DISPLAY INVISIBLE (-2750 4325);
FORCEPROP 1 LAST PATH I87
J 0
(-2700 4475);
DISPLAY 0.978723 (-2700 4475);
PAINT WHITE (-2700 4475);
DISPLAY INVISIBLE (-2700 4475);
FORCEPROP 1 LAST PART_NUMBER CH710KMEA01
J 0
(-2700 4175);
DISPLAY 0.404255 (-2700 4175);
DISPLAY INVISIBLE (-2700 4175);
FORCEADD Q_INDUCTOR..1
R 3
(-8175 4250);
FORCEPROP 1 LAST LOCATION L32
R 1
J 2
(-8335 4375);
DISPLAY 0.723404 (-8335 4375);
PAINT GREEN (-8335 4375);
FORCEPROP 0 LAST $SEC 1
R 1
J 0
(-8150 4375);
DISPLAY 0.680851 (-8150 4375);
PAINT MONO (-8150 4375);
DISPLAY INVISIBLE (-8150 4375);
FORCEPROP 0 LAST CDS_SEC 1
R 1
J 0
(-8150 4375);
DISPLAY 0.680851 (-8150 4375);
DISPLAY INVISIBLE (-8150 4375);
FORCEPROP 0 LASTPIN (-8150 4350) $PN 1
R 1
J 0
(-8160 4360);
DISPLAY 0.680851 (-8160 4360);
PAINT MONO (-8160 4360);
FORCEPROP 0 LASTPIN (-8150 4150) $PN 2
R 1
J 2
(-8160 4140);
DISPLAY 0.680851 (-8160 4140);
PAINT MONO (-8160 4140);
FORCEPROP 1 LAST MATERIAL IND
R 1
J 2
(-8230 4375);
DISPLAY 0.574468 (-8230 4375);
PAINT GREEN (-8230 4375);
FORCEPROP 2 LAST PACK_TYPE SMLF
R 1
J 2
(-8375 4375);
DISPLAY 0.553191 (-8375 4375);
FORCEPROP 2 LAST VALUE BLM15PD121SN1D/1300MA
R 1
J 2
(-8425 4375);
DISPLAY 0.553191 (-8425 4375);
FORCEPROP 2 LAST CDS_LIB pure_quanta
J 0
(-8175 4250);
DISPLAY INVISIBLE (-8175 4250);
FORCEPROP 1 LAST NEEDS_NO_SIZE TRUE
R 1
J 2
(-8175 4250);
DISPLAY 0.468085 (-8175 4250);
PAINT GREEN (-8175 4250);
DISPLAY INVISIBLE (-8175 4250);
FORCEPROP 1 LAST PATH I88
R 1
J 2
(-8230 4175);
DISPLAY 0.723404 (-8230 4175);
PAINT GREEN (-8230 4175);
DISPLAY INVISIBLE (-8230 4175);
FORCEPROP 1 LAST PART_NUMBER CX5PD121000
R 1
J 2
(-8275 4375);
DISPLAY 0.574468 (-8275 4375);
PAINT GREEN (-8275 4375);
DISPLAY INVISIBLE (-8275 4375);
FORCEADD Q_RES..2
(-8050 4225);
FORCEPROP 1 LAST LOCATION R857
J 0
(-8005 4350);
DISPLAY 0.808511 (-8005 4350);
FORCEPROP 0 LAST $SEC 1
J 0
(-8000 4400);
DISPLAY 0.680851 (-8000 4400);
PAINT MONO (-8000 4400);
DISPLAY INVISIBLE (-8000 4400);
FORCEPROP 0 LAST CDS_SEC 1
J 0
(-8000 4400);
DISPLAY 0.680851 (-8000 4400);
DISPLAY INVISIBLE (-8000 4400);
FORCEPROP 1 LASTPIN (-8050 4325) $PN 1
J 0
(-8045 4287);
DISPLAY 0.787234 (-8045 4287);
PAINT MONO (-8045 4287);
FORCEPROP 1 LASTPIN (-8050 4125) $PN 2
J 0
(-8045 4135);
DISPLAY 0.787234 (-8045 4135);
PAINT MONO (-8045 4135);
FORCEPROP 1 LAST VALUE 0
J 0
(-8005 4300);
DISPLAY 0.638298 (-8005 4300);
FORCEPROP 1 LAST TOLERANCE 5%
J 0
(-8005 4250);
DISPLAY 0.638298 (-8005 4250);
FORCEPROP 1 LAST WATTAGE 1/16W
J 0
(-8010 4200);
DISPLAY 0.638298 (-8010 4200);
FORCEPROP 1 LAST PACK_TYPE 0402LF
J 0
(-8010 4050);
DISPLAY 0.638298 (-8010 4050);
FORCEPROP 1 LAST MATERIAL EMPTY
J 0
(-8010 4150);
DISPLAY 0.638298 (-8010 4150);
PAINT RED (-8010 4150);
FORCEPROP 2 LAST CDS_LIB pure_quanta
J 0
(-8050 4225);
DISPLAY INVISIBLE (-8050 4225);
FORCEPROP 1 LAST PATH I89
J 0
(-8000 4400);
DISPLAY 0.978723 (-8000 4400);
PAINT WHITE (-8000 4400);
DISPLAY INVISIBLE (-8000 4400);
FORCEPROP 1 LAST PART_NUMBER CS00002JB13
J 0
(-8010 4100);
DISPLAY 0.638298 (-8010 4100);
DISPLAY INVISIBLE (-8010 4100);
FORCEADD P1V0..1
(-6850 3625);
FORCEPROP 3 LASTPIN (-6850 3575) SIG_NAME P1V8_CPU1_RT2_1A_1D\g
J 0
(-6840 3585);
DISPLAY 0.659574 (-6840 3585);
PAINT MONO (-6840 3585);
DISPLAY INVISIBLE (-6840 3585);
FORCEPROP 1 LAST HDL_POWER P1V8_CPU1_RT2_1A_1D
J 1
(-6850 3675);
DISPLAY 0.489362 (-6850 3675);
PAINT SKYBLUE (-6850 3675);
FORCEPROP 2 LAST CDS_LIB pure_quanta_power
J 0
(-6850 3625);
DISPLAY INVISIBLE (-6850 3625);
FORCEPROP 1 LAST PATH I9
J 0
(-6800 3650);
DISPLAY 0.872340 (-6800 3650);
PAINT AQUA (-6800 3650);
DISPLAY INVISIBLE (-6800 3650);
FORCEADD Q_CAP..1
(-2975 1275);
FORCEPROP 1 LAST LOCATION C390
J 0
(-2925 1375);
DISPLAY 0.978723 (-2925 1375);
PAINT WHITE (-2925 1375);
FORCEPROP 0 LAST $SEC 1
J 0
(-2925 1425);
DISPLAY 0.680851 (-2925 1425);
PAINT MONO (-2925 1425);
DISPLAY INVISIBLE (-2925 1425);
FORCEPROP 0 LAST CDS_SEC 1
J 0
(-2925 1425);
DISPLAY 0.680851 (-2925 1425);
DISPLAY INVISIBLE (-2925 1425);
FORCEPROP 1 LASTPIN (-2975 1375) $PN 1
J 0
(-2965 1355);
DISPLAY 0.787234 (-2965 1355);
PAINT MONO (-2965 1355);
FORCEPROP 1 LASTPIN (-2975 1175) $PN 2
J 0
(-2965 1155);
DISPLAY 0.787234 (-2965 1155);
PAINT MONO (-2965 1155);
FORCEPROP 1 LAST VOLTAGE 4V
J 0
(-2925 1275);
DISPLAY 0.510638 (-2925 1275);
FORCEPROP 1 LAST VALUE 1UF
J 0
(-2925 1325);
DISPLAY 0.510638 (-2925 1325);
FORCEPROP 1 LAST TOLERANCE 20%
J 0
(-2925 1225);
DISPLAY 0.510638 (-2925 1225);
FORCEPROP 1 LAST MATERIAL X6S
J 0
(-2925 1175);
DISPLAY 0.510638 (-2925 1175);
FORCEPROP 1 LAST PACK_TYPE 0201
J 0
(-2925 1125);
DISPLAY 0.510638 (-2925 1125);
FORCEPROP 2 LAST CDS_LIB pure_quanta
J 0
(-2975 1275);
DISPLAY INVISIBLE (-2975 1275);
FORCEPROP 1 LAST PATH I90
J 0
(-2925 1425);
DISPLAY 0.978723 (-2925 1425);
PAINT WHITE (-2925 1425);
DISPLAY INVISIBLE (-2925 1425);
FORCEPROP 1 LAST PART_NUMBER CH-10KMEE00
J 0
(-2925 1125);
DISPLAY 0.510638 (-2925 1125);
DISPLAY INVISIBLE (-2925 1125);
FORCEADD Q_CAP..1
(-2725 1275);
FORCEPROP 1 LAST LOCATION C394
J 0
(-2675 1375);
DISPLAY 0.978723 (-2675 1375);
PAINT WHITE (-2675 1375);
FORCEPROP 0 LAST $SEC 1
J 0
(-2675 1425);
DISPLAY 0.680851 (-2675 1425);
PAINT MONO (-2675 1425);
DISPLAY INVISIBLE (-2675 1425);
FORCEPROP 0 LAST CDS_SEC 1
J 0
(-2675 1425);
DISPLAY 0.680851 (-2675 1425);
DISPLAY INVISIBLE (-2675 1425);
FORCEPROP 1 LASTPIN (-2725 1375) $PN 1
J 0
(-2715 1355);
DISPLAY 0.787234 (-2715 1355);
PAINT MONO (-2715 1355);
FORCEPROP 1 LASTPIN (-2725 1175) $PN 2
J 0
(-2715 1155);
DISPLAY 0.787234 (-2715 1155);
PAINT MONO (-2715 1155);
FORCEPROP 1 LAST PACK_TYPE 0201
J 0
(-2675 1125);
DISPLAY 0.510638 (-2675 1125);
FORCEPROP 1 LAST MATERIAL X6S
J 0
(-2675 1175);
DISPLAY 0.510638 (-2675 1175);
FORCEPROP 1 LAST TOLERANCE 20%
J 0
(-2675 1225);
DISPLAY 0.510638 (-2675 1225);
FORCEPROP 1 LAST VALUE 1UF
J 0
(-2675 1325);
DISPLAY 0.510638 (-2675 1325);
FORCEPROP 1 LAST VOLTAGE 4V
J 0
(-2675 1275);
DISPLAY 0.510638 (-2675 1275);
FORCEPROP 2 LAST CDS_LIB pure_quanta
J 0
(-2725 1275);
DISPLAY INVISIBLE (-2725 1275);
FORCEPROP 1 LAST PATH I91
J 0
(-2675 1425);
DISPLAY 0.978723 (-2675 1425);
PAINT WHITE (-2675 1425);
DISPLAY INVISIBLE (-2675 1425);
FORCEPROP 1 LAST PART_NUMBER CH-10KMEE00
J 0
(-2675 1125);
DISPLAY 0.510638 (-2675 1125);
DISPLAY INVISIBLE (-2675 1125);
FORCEADD Q_CAP..1
(-1800 3050);
FORCEPROP 1 LAST LOCATION C426
J 0
(-1750 3150);
DISPLAY 0.978723 (-1750 3150);
PAINT WHITE (-1750 3150);
FORCEPROP 0 LAST $SEC 1
J 0
(-1750 3200);
DISPLAY 0.680851 (-1750 3200);
PAINT MONO (-1750 3200);
DISPLAY INVISIBLE (-1750 3200);
FORCEPROP 0 LAST CDS_SEC 1
J 0
(-1750 3200);
DISPLAY 0.680851 (-1750 3200);
DISPLAY INVISIBLE (-1750 3200);
FORCEPROP 1 LASTPIN (-1800 3150) $PN 1
J 0
(-1790 3130);
DISPLAY 0.787234 (-1790 3130);
PAINT MONO (-1790 3130);
FORCEPROP 1 LASTPIN (-1800 2950) $PN 2
J 0
(-1790 2930);
DISPLAY 0.787234 (-1790 2930);
PAINT MONO (-1790 2930);
FORCEPROP 1 LAST VALUE 0.1UF
J 0
(-1750 3100);
DISPLAY 0.638298 (-1750 3100);
FORCEPROP 1 LAST VOLTAGE 10V
J 0
(-1750 3050);
DISPLAY 0.638298 (-1750 3050);
FORCEPROP 1 LAST PACK_TYPE C0201
J 0
(-1750 2900);
DISPLAY 0.638298 (-1750 2900);
FORCEPROP 1 LAST MATERIAL X7S
J 0
(-1750 2950);
DISPLAY 0.638298 (-1750 2950);
FORCEPROP 1 LAST TOLERANCE 10%
J 0
(-1750 3000);
DISPLAY 0.638298 (-1750 3000);
FORCEPROP 2 LAST CDS_LIB pure_quanta
J 0
(-1800 3050);
DISPLAY INVISIBLE (-1800 3050);
FORCEPROP 1 LAST PATH I92
J 0
(-1750 3200);
DISPLAY 0.978723 (-1750 3200);
PAINT WHITE (-1750 3200);
DISPLAY INVISIBLE (-1750 3200);
FORCEPROP 1 LAST PART_NUMBER CH4102K6E00
J 0
(-1750 2900);
DISPLAY 0.978723 (-1750 2900);
DISPLAY INVISIBLE (-1750 2900);
FORCEADD Q_CAP..1
(-1550 3050);
FORCEPROP 1 LAST LOCATION C428
J 0
(-1500 3150);
DISPLAY 0.978723 (-1500 3150);
PAINT WHITE (-1500 3150);
FORCEPROP 0 LAST $SEC 1
J 0
(-1500 3200);
DISPLAY 0.680851 (-1500 3200);
PAINT MONO (-1500 3200);
DISPLAY INVISIBLE (-1500 3200);
FORCEPROP 0 LAST CDS_SEC 1
J 0
(-1500 3200);
DISPLAY 0.680851 (-1500 3200);
DISPLAY INVISIBLE (-1500 3200);
FORCEPROP 1 LASTPIN (-1550 3150) $PN 1
J 0
(-1540 3130);
DISPLAY 0.787234 (-1540 3130);
PAINT MONO (-1540 3130);
FORCEPROP 1 LASTPIN (-1550 2950) $PN 2
J 0
(-1540 2930);
DISPLAY 0.787234 (-1540 2930);
PAINT MONO (-1540 2930);
FORCEPROP 1 LAST TOLERANCE 10%
J 0
(-1500 3000);
DISPLAY 0.638298 (-1500 3000);
FORCEPROP 1 LAST PACK_TYPE C0201
J 0
(-1500 2900);
DISPLAY 0.638298 (-1500 2900);
FORCEPROP 1 LAST MATERIAL X7S
J 0
(-1500 2950);
DISPLAY 0.638298 (-1500 2950);
FORCEPROP 1 LAST VOLTAGE 10V
J 0
(-1500 3050);
DISPLAY 0.638298 (-1500 3050);
FORCEPROP 1 LAST VALUE 0.1UF
J 0
(-1500 3100);
DISPLAY 0.638298 (-1500 3100);
FORCEPROP 2 LAST CDS_LIB pure_quanta
J 0
(-1550 3050);
DISPLAY INVISIBLE (-1550 3050);
FORCEPROP 1 LAST PATH I93
J 0
(-1500 3200);
DISPLAY 0.978723 (-1500 3200);
PAINT WHITE (-1500 3200);
DISPLAY INVISIBLE (-1500 3200);
FORCEPROP 1 LAST PART_NUMBER CH4102K6E00
J 0
(-1500 2900);
DISPLAY 0.978723 (-1500 2900);
DISPLAY INVISIBLE (-1500 2900);
FORCEADD Q_CAPP..1
(-1500 5600);
FORCEPROP 1 LAST LOCATION C7004
J 0
(-1450 5700);
DISPLAY 0.638298 (-1450 5700);
FORCEPROP 0 LAST $SEC 1
J 0
(-1450 5750);
DISPLAY 0.680851 (-1450 5750);
PAINT MONO (-1450 5750);
DISPLAY INVISIBLE (-1450 5750);
FORCEPROP 0 LAST CDS_SEC 1
J 0
(-1450 5750);
DISPLAY 0.680851 (-1450 5750);
DISPLAY INVISIBLE (-1450 5750);
FORCEPROP 1 LASTPIN (-1500 5700) $PN 1
J 0
(-1490 5685);
DISPLAY 0.787234 (-1490 5685);
PAINT MONO (-1490 5685);
FORCEPROP 1 LASTPIN (-1500 5500) $PN 2
J 0
(-1490 5485);
DISPLAY 0.787234 (-1490 5485);
PAINT MONO (-1490 5485);
FORCEPROP 1 LAST VALUE 470UF
J 0
(-1450 5650);
DISPLAY 0.510638 (-1450 5650);
FORCEPROP 1 LAST MATERIAL SPCAP
J 0
(-1450 5500);
DISPLAY 0.510638 (-1450 5500);
FORCEPROP 1 LAST TOLERANCE 20%
J 0
(-1450 5600);
DISPLAY 0.510638 (-1450 5600);
FORCEPROP 1 LAST VOLTAGE 2.5V
J 0
(-1450 5550);
DISPLAY 0.510638 (-1450 5550);
FORCEPROP 1 LAST PACK_TYPE SMLF
J 0
(-1450 5450);
DISPLAY 0.510638 (-1450 5450);
FORCEPROP 2 LAST CDS_LIB pure_quanta
J 0
(-1500 5600);
DISPLAY INVISIBLE (-1500 5600);
FORCEPROP 1 LAST PATH I94
J 0
(-1450 5750);
DISPLAY 0.978723 (-1450 5750);
DISPLAY INVISIBLE (-1450 5750);
FORCEPROP 1 LAST PART_NUMBER CH747LM8818
J 0
(-1450 5400);
DISPLAY 0.404255 (-1450 5400);
DISPLAY INVISIBLE (-1450 5400);
FORCEADD Q_CAPP..1
(-1200 5600);
FORCEPROP 1 LAST LOCATION C7005
J 0
(-1150 5700);
DISPLAY 0.787234 (-1150 5700);
FORCEPROP 0 LAST $SEC 1
J 0
(-1150 5750);
DISPLAY 0.680851 (-1150 5750);
PAINT MONO (-1150 5750);
DISPLAY INVISIBLE (-1150 5750);
FORCEPROP 0 LAST CDS_SEC 1
J 0
(-1150 5750);
DISPLAY 0.680851 (-1150 5750);
DISPLAY INVISIBLE (-1150 5750);
FORCEPROP 1 LASTPIN (-1200 5700) $PN 1
J 0
(-1190 5685);
DISPLAY 0.787234 (-1190 5685);
PAINT MONO (-1190 5685);
FORCEPROP 1 LASTPIN (-1200 5500) $PN 2
J 0
(-1190 5485);
DISPLAY 0.787234 (-1190 5485);
PAINT MONO (-1190 5485);
FORCEPROP 1 LAST TOLERANCE 20%
J 0
(-1150 5600);
DISPLAY 0.510638 (-1150 5600);
FORCEPROP 1 LAST PACK_TYPE SMLF
J 0
(-1150 5450);
DISPLAY 0.510638 (-1150 5450);
FORCEPROP 1 LAST VALUE 470UF
J 0
(-1150 5650);
DISPLAY 0.510638 (-1150 5650);
FORCEPROP 1 LAST MATERIAL SPCAP
J 0
(-1150 5500);
DISPLAY 0.510638 (-1150 5500);
FORCEPROP 1 LAST VOLTAGE 2.5V
J 0
(-1150 5550);
DISPLAY 0.510638 (-1150 5550);
FORCEPROP 2 LAST CDS_LIB pure_quanta
J 0
(-1200 5600);
DISPLAY INVISIBLE (-1200 5600);
FORCEPROP 1 LAST PATH I95
J 0
(-1150 5750);
DISPLAY 0.978723 (-1150 5750);
DISPLAY INVISIBLE (-1150 5750);
FORCEPROP 1 LAST PART_NUMBER CH747LM8818
J 0
(-1150 5400);
DISPLAY 0.404255 (-1150 5400);
DISPLAY INVISIBLE (-1150 5400);
FORCEADD Q_CAP..1
(-900 5600);
FORCEPROP 1 LAST LOCATION C7006
J 0
(-850 5700);
DISPLAY 0.638298 (-850 5700);
FORCEPROP 0 LAST $SEC 1
J 0
(-850 5750);
DISPLAY 0.680851 (-850 5750);
PAINT MONO (-850 5750);
DISPLAY INVISIBLE (-850 5750);
FORCEPROP 0 LAST CDS_SEC 1
J 0
(-850 5750);
DISPLAY 0.680851 (-850 5750);
DISPLAY INVISIBLE (-850 5750);
FORCEPROP 1 LASTPIN (-900 5700) $PN 1
J 0
(-890 5680);
DISPLAY 0.787234 (-890 5680);
PAINT MONO (-890 5680);
FORCEPROP 1 LASTPIN (-900 5500) $PN 2
J 0
(-890 5480);
DISPLAY 0.787234 (-890 5480);
PAINT MONO (-890 5480);
FORCEPROP 1 LAST TOLERANCE 20%
J 0
(-850 5550);
DISPLAY 0.638298 (-850 5550);
FORCEPROP 1 LAST PACK_TYPE C0805
J 0
(-850 5400);
DISPLAY 0.638298 (-850 5400);
FORCEPROP 1 LAST VALUE 47UF
J 0
(-850 5650);
DISPLAY 0.638298 (-850 5650);
FORCEPROP 1 LAST MATERIAL X6S
J 0
(-850 5500);
DISPLAY 0.638298 (-850 5500);
FORCEPROP 1 LAST VOLTAGE 4V
J 0
(-850 5600);
DISPLAY 0.638298 (-850 5600);
FORCEPROP 2 LAST CDS_LIB pure_quanta
J 0
(-900 5600);
DISPLAY INVISIBLE (-900 5600);
FORCEPROP 1 LAST PATH I96
J 0
(-850 5750);
DISPLAY 0.978723 (-850 5750);
PAINT WHITE (-850 5750);
DISPLAY INVISIBLE (-850 5750);
FORCEPROP 1 LAST PART_NUMBER CH647KMEA04
J 0
(-850 5450);
DISPLAY 0.638298 (-850 5450);
DISPLAY INVISIBLE (-850 5450);
FORCEADD Q_CAP..1
(-500 5575);
FORCEPROP 1 LAST LOCATION C7007
J 0
(-450 5675);
DISPLAY 0.978723 (-450 5675);
FORCEPROP 0 LAST $SEC 1
J 0
(-450 5725);
DISPLAY 0.680851 (-450 5725);
PAINT MONO (-450 5725);
DISPLAY INVISIBLE (-450 5725);
FORCEPROP 0 LAST CDS_SEC 1
J 0
(-450 5725);
DISPLAY 0.680851 (-450 5725);
DISPLAY INVISIBLE (-450 5725);
FORCEPROP 1 LASTPIN (-500 5675) $PN 1
J 0
(-490 5655);
DISPLAY 0.787234 (-490 5655);
PAINT MONO (-490 5655);
FORCEPROP 1 LASTPIN (-500 5475) $PN 2
J 0
(-490 5455);
DISPLAY 0.787234 (-490 5455);
PAINT MONO (-490 5455);
FORCEPROP 1 LAST TOLERANCE 20%
J 0
(-450 5525);
DISPLAY 0.638298 (-450 5525);
FORCEPROP 1 LAST MATERIAL X6S
J 0
(-450 5475);
DISPLAY 0.638298 (-450 5475);
FORCEPROP 1 LAST VALUE 47UF
J 0
(-450 5625);
DISPLAY 0.638298 (-450 5625);
FORCEPROP 1 LAST PACK_TYPE C0805
J 0
(-450 5425);
DISPLAY 0.638298 (-450 5425);
FORCEPROP 1 LAST VOLTAGE 4V
J 0
(-450 5575);
DISPLAY 0.638298 (-450 5575);
FORCEPROP 2 LAST CDS_LIB pure_quanta
J 0
(-500 5575);
DISPLAY INVISIBLE (-500 5575);
FORCEPROP 1 LAST PATH I97
J 0
(-450 5725);
DISPLAY 0.978723 (-450 5725);
PAINT WHITE (-450 5725);
DISPLAY INVISIBLE (-450 5725);
FORCEPROP 1 LAST PART_NUMBER CH647KMEA04
J 0
(-450 5425);
DISPLAY 0.638298 (-450 5425);
DISPLAY INVISIBLE (-450 5425);
FORCEADD Q_CAPP..1
(-1025 2400);
FORCEPROP 1 LAST LOCATION C7026
J 0
(-975 2500);
DISPLAY 0.787234 (-975 2500);
FORCEPROP 0 LAST $SEC 1
J 0
(-975 2550);
DISPLAY 0.680851 (-975 2550);
PAINT MONO (-975 2550);
DISPLAY INVISIBLE (-975 2550);
FORCEPROP 0 LAST CDS_SEC 1
J 0
(-975 2550);
DISPLAY 0.680851 (-975 2550);
DISPLAY INVISIBLE (-975 2550);
FORCEPROP 1 LASTPIN (-1025 2500) $PN 1
J 0
(-1015 2485);
DISPLAY 0.787234 (-1015 2485);
PAINT MONO (-1015 2485);
FORCEPROP 1 LASTPIN (-1025 2300) $PN 2
J 0
(-1015 2285);
DISPLAY 0.787234 (-1015 2285);
PAINT MONO (-1015 2285);
FORCEPROP 1 LAST TOLERANCE 20%
J 0
(-975 2400);
DISPLAY 0.510638 (-975 2400);
FORCEPROP 1 LAST VALUE 470UF
J 0
(-975 2450);
DISPLAY 0.510638 (-975 2450);
FORCEPROP 1 LAST PACK_TYPE SMLF
J 0
(-975 2250);
DISPLAY 0.510638 (-975 2250);
FORCEPROP 1 LAST VOLTAGE 2.5V
J 0
(-975 2350);
DISPLAY 0.510638 (-975 2350);
FORCEPROP 1 LAST MATERIAL SPCAP
J 0
(-975 2300);
DISPLAY 0.510638 (-975 2300);
FORCEPROP 2 LAST CDS_LIB pure_quanta
J 0
(-1025 2400);
DISPLAY INVISIBLE (-1025 2400);
FORCEPROP 1 LAST PATH I98
J 0
(-975 2550);
DISPLAY 0.978723 (-975 2550);
DISPLAY INVISIBLE (-975 2550);
FORCEPROP 1 LAST PART_NUMBER CH747LM8818
J 0
(-975 2200);
DISPLAY 0.404255 (-975 2200);
DISPLAY INVISIBLE (-975 2200);
FORCEADD Q_CAPP..1
(-725 2400);
FORCEPROP 1 LAST LOCATION C7027
J 0
(-675 2500);
DISPLAY 0.787234 (-675 2500);
FORCEPROP 0 LAST $SEC 1
J 0
(-675 2550);
DISPLAY 0.680851 (-675 2550);
PAINT MONO (-675 2550);
DISPLAY INVISIBLE (-675 2550);
FORCEPROP 0 LAST CDS_SEC 1
J 0
(-675 2550);
DISPLAY 0.680851 (-675 2550);
DISPLAY INVISIBLE (-675 2550);
FORCEPROP 1 LASTPIN (-725 2500) $PN 1
J 0
(-715 2485);
DISPLAY 0.787234 (-715 2485);
PAINT MONO (-715 2485);
FORCEPROP 1 LASTPIN (-725 2300) $PN 2
J 0
(-715 2285);
DISPLAY 0.787234 (-715 2285);
PAINT MONO (-715 2285);
FORCEPROP 1 LAST VOLTAGE 2.5V
J 0
(-675 2350);
DISPLAY 0.510638 (-675 2350);
FORCEPROP 1 LAST PACK_TYPE SMLF
J 0
(-675 2250);
DISPLAY 0.510638 (-675 2250);
FORCEPROP 1 LAST MATERIAL SPCAP
J 0
(-675 2300);
DISPLAY 0.510638 (-675 2300);
FORCEPROP 1 LAST TOLERANCE 20%
J 0
(-675 2400);
DISPLAY 0.510638 (-675 2400);
FORCEPROP 1 LAST VALUE 470UF
J 0
(-675 2450);
DISPLAY 0.510638 (-675 2450);
FORCEPROP 2 LAST CDS_LIB pure_quanta
J 0
(-725 2400);
DISPLAY INVISIBLE (-725 2400);
FORCEPROP 1 LAST PATH I99
J 0
(-675 2550);
DISPLAY 0.978723 (-675 2550);
DISPLAY INVISIBLE (-675 2550);
FORCEPROP 1 LAST PART_NUMBER CH747LM8818
J 0
(-675 2200);
DISPLAY 0.404255 (-675 2200);
DISPLAY INVISIBLE (-675 2200);
FORCEADD DNS..2
(-7950 4225);
PAINT RED (-7950 4225);
FORCEPROP 2 LAST CDS_LIB mstr_misc
J 0
(-7950 4225);
DISPLAY INVISIBLE (-7950 4225);
FORCEPROP 1 LAST COMMENT_BODY TRUE
J 0
(-7950 4225);
DISPLAY INVISIBLE (-7950 4225);
FORCEADD DNS..2
(-7625 3850);
PAINT RED (-7625 3850);
FORCEPROP 2 LAST CDS_LIB mstr_misc
J 0
(-7625 3850);
DISPLAY INVISIBLE (-7625 3850);
FORCEPROP 1 LAST COMMENT_BODY TRUE
J 0
(-7625 3850);
DISPLAY INVISIBLE (-7625 3850);
FORCEADD CAD_NOTE..1
(-8100 3075);
FORCEPROP 0 LAST S1 L32/R857 COLAY WITH R852/R853
J 0
(-8225 2950);
DISPLAY 0.808511 (-8225 2950);
PAINT WHITE (-8225 2950);
FORCEPROP 2 LAST CDS_LIB pure_quanta_power
J 0
(-8100 3075);
DISPLAY INVISIBLE (-8100 3075);
FORCEPROP 1 LAST COMMENT_BODY TRUE
J 0
(-8075 3175);
DISPLAY 0.978723 (-8075 3175);
DISPLAY INVISIBLE (-8075 3175);
FORCEADD DNS..2
(-7625 3675);
PAINT RED (-7625 3675);
FORCEPROP 2 LAST CDS_LIB mstr_misc
J 0
(-7625 3675);
DISPLAY INVISIBLE (-7625 3675);
FORCEPROP 1 LAST COMMENT_BODY TRUE
J 0
(-7625 3675);
DISPLAY INVISIBLE (-7625 3675);
FORCEADD CAD_NOTE..1
(-5050 2575);
FORCEPROP 0 LAST S1 R858 AND R859 COLAY
J 0
(-5175 2450);
DISPLAY 0.808511 (-5175 2450);
PAINT WHITE (-5175 2450);
FORCEPROP 2 LAST CDS_LIB pure_quanta_power
J 0
(-5050 2575);
DISPLAY INVISIBLE (-5050 2575);
FORCEPROP 1 LAST COMMENT_BODY TRUE
J 0
(-5025 2675);
DISPLAY 0.978723 (-5025 2675);
DISPLAY INVISIBLE (-5025 2675);
FORCEADD DNS..2
(-4300 2875);
PAINT RED (-4300 2875);
FORCEPROP 2 LAST CDS_LIB mstr_misc
J 0
(-4300 2875);
DISPLAY INVISIBLE (-4300 2875);
FORCEPROP 1 LAST COMMENT_BODY TRUE
J 0
(-4300 2875);
DISPLAY INVISIBLE (-4300 2875);
FORCEADD QUANTA_TITLE_BLOCK_C..1
(0 0);
FORCEPROP 0 LAST CDS_CON_LAST_MODIFIED Thu Sep 14 16:13:06 2023
J 0
(-1885 15);
DISPLAY INVISIBLE (-1885 15);
FORCEPROP 1 LAST CUSTOM_TXT_CDS <CON_LAST_MODIFIED>
J 0
(-1885 15);
DISPLAY 0.978723 (-1885 15);
FORCEPROP 2 LAST CUSTOM_TXT_CDS <XR_PAGE_TITLE>
J 0
(-7890 5250);
DISPLAY 0.638298 (-7890 5250);
PAINT PINK (-7890 5250);
DISPLAY INVISIBLE (-7890 5250);
FORCEPROP 1 LAST CUSTOM_TXT_CDS <NAME_2>
J 0
(-3175 50);
FORCEPROP 1 LAST CUSTOM_TXT_CDS <NAME_1>
J 0
(-3175 175);
FORCEPROP 1 LAST CUSTOM_TXT_CDS <Q_NUMBER>
J 0
(-1403 103);
DISPLAY 1.212766 (-1403 103);
FORCEPROP 1 LAST CUSTOM_TXT_CDS <Q_PROJ>
J 0
(-2382 102);
DISPLAY 1.212766 (-2382 102);
FORCEPROP 1 LAST CUSTOM_TXT_CDS <Q_REV>
J 0
(-184 103);
DISPLAY 1.212766 (-184 103);
FORCEPROP 1 LAST CUSTOM_TXT_CDS <CON_PAGE_NUM> OF <CON_TOTAL_PAGES>
J 0
(-446 18);
DISPLAY 0.978723 (-446 18);
FORCEPROP 1 LAST Q_TITLE RETIMER_CPU1_P2 DECAPS(8)
J 0
(-9366 26);
DISPLAY 2.446809 (-9366 26);
PAINT GREEN (-9366 26);
FORCEPROP 2 LAST CDS_LIB pure_quanta
J 0
(0 0);
DISPLAY INVISIBLE (0 0);
FORCEPROP 1 LAST CDS_LMAN_SYM_OUTLINE -9475,6775,100,-125
J 0
(0 0);
DISPLAY 0.468085 (0 0);
PAINT GREEN (0 0);
DISPLAY INVISIBLE (0 0);
FORCEPROP 2 LAST PAGE_BORDER TRUE
J 0
(-7890 5250);
DISPLAY 0.638298 (-7890 5250);
PAINT PINK (-7890 5250);
DISPLAY INVISIBLE (-7890 5250);
FORCEPROP 2 LAST CDS_XR_PAGE_TITLE CR-346 : @T6G_MB_LIB.T6G(SCH_1):PAGE346
J 0
(-7890 5250);
DISPLAY 0.638298 (-7890 5250);
PAINT PINK (-7890 5250);
DISPLAY INVISIBLE (-7890 5250);
FORCEPROP 1 LAST Q_DEPT BU9
J 1
(-3763 49);
DISPLAY 1.957447 (-3763 49);
PAINT GREEN (-3763 49);
DISPLAY INVISIBLE (-3763 49);
FORCEPROP 1 LAST COMMENT_BODY TRUE
J 0
(12 -13);
DISPLAY 0.978723 (12 -13);
PAINT GREEN (12 -13);
DISPLAY INVISIBLE (12 -13);
WIRE 16 -1 (-425 2625)(-425 2500);
WIRE 16 -1 (-725 2625)(-425 2625);
WIRE 16 -1 (-725 2500)(-725 2625);
WIRE 16 -1 (-1025 2625)(-725 2625);
WIRE 16 -1 (-1325 2625)(-1025 2625);
WIRE 16 -1 (-1025 2500)(-1025 2625);
WIRE 16 -1 (-1325 2475)(-1325 2625);
WIRE 16 -1 (-1325 2625)(-1575 2625);
WIRE 16 -1 (-1850 2625)(-1575 2625);
WIRE 16 -1 (-1575 2475)(-1575 2625);
WIRE 16 -1 (-1850 2475)(-1850 2625);
WIRE 16 -1 (-2125 2625)(-1850 2625);
WIRE 16 -1 (-2375 2625)(-2125 2625);
WIRE 16 -1 (-2125 2475)(-2125 2625);
WIRE 16 -1 (-2375 2475)(-2375 2625);
WIRE 16 -1 (-2625 2625)(-2375 2625);
WIRE 16 -1 (-2850 2625)(-2625 2625);
WIRE 16 -1 (-2625 2625)(-2625 2475);
WIRE 16 -1 (-2850 2625)(-2850 2475);
WIRE 16 -1 (-3150 2625)(-2850 2625);
WIRE 16 -1 (-3150 2625)(-3150 2475);
WIRE 16 -1 (-3600 2625)(-3150 2625);
WIRE 16 -1 (-3600 3300)(-3600 2625);
WIRE 16 -1 (-3600 2625)(-3775 2625);
WIRE 16 -1 (-3600 3300)(-3425 3300);
WIRE 16 -1 (-3600 3925)(-3600 3300);
WIRE 16 -1 (-3600 4575)(-3600 3925);
WIRE 16 -1 (-3600 3925)(-3425 3925);
WIRE 16 -1 (-3425 3300)(-3200 3300);
WIRE 16 -1 (-3425 3300)(-3425 3175);
WIRE 16 -1 (-3200 3300)(-2950 3300);
WIRE 16 -1 (-3200 3300)(-3200 3175);
WIRE 16 -1 (-3425 3925)(-3200 3925);
WIRE 16 -1 (-3425 3800)(-3425 3925);
WIRE 16 -1 (-3600 4575)(-3425 4575);
WIRE 16 -1 (-3675 4575)(-3600 4575);
WIRE 16 -1 (-3425 4925)(-3425 4575);
WIRE 16 -1 (-3425 4575)(-3200 4575);
WIRE 16 -1 (-3425 4575)(-3425 4425);
WIRE 16 -1 (-3200 3925)(-2975 3925);
WIRE 16 -1 (-3200 3800)(-3200 3925);
WIRE 16 -1 (-2950 3300)(-2725 3300);
WIRE 16 -1 (-2950 3300)(-2950 3175);
WIRE 16 -1 (-2725 3300)(-2475 3300);
WIRE 16 -1 (-2725 3300)(-2725 3175);
WIRE 16 -1 (-2975 3925)(-2750 3925);
WIRE 16 -1 (-2975 3800)(-2975 3925);
WIRE 16 -1 (-2975 4575)(-3200 4575);
WIRE 16 -1 (-3200 4575)(-3200 4425);
WIRE 16 -1 (-2750 4575)(-2975 4575);
WIRE 16 -1 (-2975 4575)(-2975 4425);
WIRE 16 -1 (-2750 3925)(-2500 3925);
WIRE 16 -1 (-2750 3800)(-2750 3925);
WIRE 16 -1 (-2475 3300)(-2250 3300);
WIRE 16 -1 (-2475 3300)(-2475 3175);
WIRE 16 -1 (-2250 3300)(-2025 3300);
WIRE 16 -1 (-2250 3300)(-2250 3150);
WIRE 16 -1 (-2500 3925)(-2275 3925);
WIRE 16 -1 (-2500 3800)(-2500 3925);
WIRE 16 -1 (-2500 4575)(-2750 4575);
WIRE 16 -1 (-2750 4575)(-2750 4425);
WIRE 16 -1 (-2275 4575)(-2500 4575);
WIRE 16 -1 (-2500 4575)(-2500 4425);
WIRE 16 -1 (-2275 3925)(-2050 3925);
WIRE 16 -1 (-2275 3800)(-2275 3925);
WIRE 16 -1 (-1800 3300)(-2025 3300);
WIRE 16 -1 (-2025 3150)(-2025 3300);
WIRE 16 -1 (-1800 3300)(-1550 3300);
WIRE 16 -1 (-1800 3150)(-1800 3300);
WIRE 16 -1 (-2050 3925)(-1825 3925);
WIRE 16 -1 (-2050 3800)(-2050 3925);
WIRE 16 -1 (-2050 4575)(-2275 4575);
WIRE 16 -1 (-2275 4575)(-2275 4425);
WIRE 16 -1 (-1825 4575)(-2050 4575);
WIRE 16 -1 (-2050 4575)(-2050 4425);
WIRE 16 -1 (-1825 3925)(-1600 3925);
WIRE 16 -1 (-1825 3800)(-1825 3925);
WIRE 16 -1 (-1550 3300)(-1550 3150);
WIRE 16 -1 (-1350 3925)(-1600 3925);
WIRE 16 -1 (-1600 3800)(-1600 3925);
WIRE 16 -1 (-1525 4575)(-1825 4575);
WIRE 16 -1 (-1825 4575)(-1825 4425);
WIRE 16 -1 (-1525 4575)(-1225 4575);
WIRE 16 -1 (-1525 4575)(-1525 4425);
WIRE 16 -1 (-1350 3925)(-1350 3800);
WIRE 16 -1 (-1225 4575)(-1225 4425);
WIRE 16 -1 (-3425 3600)(-3425 3475);
WIRE 16 -1 (-3425 3475)(-3200 3475);
WIRE 16 -1 (-3200 3475)(-2975 3475);
WIRE 16 -1 (-3200 3600)(-3200 3475);
WIRE 16 -1 (-2975 3600)(-2975 3475);
WIRE 16 -1 (-2975 3475)(-2750 3475);
WIRE 16 -1 (-2750 3475)(-2500 3475);
WIRE 16 -1 (-2750 3600)(-2750 3475);
WIRE 16 -1 (-2500 3600)(-2500 3475);
WIRE 16 -1 (-2500 3475)(-2275 3475);
WIRE 16 -1 (-2275 3600)(-2275 3475);
WIRE 16 -1 (-2275 3475)(-2050 3475);
WIRE 16 -1 (-2050 3475)(-1825 3475);
WIRE 16 -1 (-2050 3600)(-2050 3475);
WIRE 16 -1 (-1825 3600)(-1825 3475);
WIRE 16 -1 (-1825 3475)(-1600 3475);
WIRE 16 -1 (-1350 3475)(-1600 3475);
WIRE 16 -1 (-1600 3600)(-1600 3475);
WIRE 16 -1 (-825 3475)(-1350 3475);
WIRE 16 -1 (-1350 3600)(-1350 3475);
WIRE 16 -1 (-825 4075)(-825 3475);
WIRE 16 -1 (-825 3475)(-825 2750);
WIRE 16 -1 (-825 2750)(-1550 2750);
WIRE 16 -1 (-825 2750)(-825 2700);
WIRE 16 -1 (-825 4075)(-1225 4075);
WIRE 16 -1 (-1225 4225)(-1225 4075);
WIRE 16 -1 (-1225 4075)(-1525 4075);
WIRE 16 -1 (-1800 2750)(-1550 2750);
WIRE 16 -1 (-1550 2950)(-1550 2750);
WIRE 16 -1 (-1800 2950)(-1800 2750);
WIRE 16 -1 (-1800 2750)(-2025 2750);
WIRE 16 -1 (-1525 4225)(-1525 4075);
WIRE 16 -1 (-1525 4075)(-1825 4075);
WIRE 16 -1 (-1825 4225)(-1825 4075);
WIRE 16 -1 (-1825 4075)(-2050 4075);
WIRE 16 -1 (-2025 2950)(-2025 2750);
WIRE 16 -1 (-2250 2750)(-2025 2750);
WIRE 16 -1 (-2250 2950)(-2250 2750);
WIRE 16 -1 (-2475 2750)(-2250 2750);
WIRE 16 -1 (-2050 4225)(-2050 4075);
WIRE 16 -1 (-2050 4075)(-2275 4075);
WIRE 16 -1 (-2275 4225)(-2275 4075);
WIRE 16 -1 (-2275 4075)(-2500 4075);
WIRE 16 -1 (-2475 2975)(-2475 2750);
WIRE 16 -1 (-2725 2750)(-2475 2750);
WIRE 16 -1 (-2725 2975)(-2725 2750);
WIRE 16 -1 (-2950 2750)(-2725 2750);
WIRE 16 -1 (-2500 4225)(-2500 4075);
WIRE 16 -1 (-2500 4075)(-2750 4075);
WIRE 16 -1 (-2750 4225)(-2750 4075);
WIRE 16 -1 (-2975 4075)(-2750 4075);
WIRE 16 -1 (-2950 2975)(-2950 2750);
WIRE 16 -1 (-3200 2750)(-2950 2750);
WIRE 16 -1 (-3200 2975)(-3200 2750);
WIRE 16 -1 (-3425 2750)(-3200 2750);
WIRE 16 -1 (-2975 4225)(-2975 4075);
WIRE 16 -1 (-3200 4075)(-2975 4075);
WIRE 16 -1 (-3200 4225)(-3200 4075);
WIRE 16 -1 (-3425 4075)(-3200 4075);
WIRE 16 -1 (-3425 2975)(-3425 2750);
WIRE 16 -1 (-3425 4225)(-3425 4075);
WIRE 16 -1 (-500 5825)(-500 5675);
WIRE 16 -1 (-900 5825)(-500 5825);
WIRE 16 -1 (-900 5700)(-900 5825);
WIRE 16 -1 (-1200 5825)(-900 5825);
WIRE 16 -1 (-1200 5700)(-1200 5825);
WIRE 16 -1 (-1500 5825)(-1200 5825);
WIRE 16 -1 (-1500 5700)(-1500 5825);
WIRE 16 -1 (-1800 5825)(-1500 5825);
WIRE 16 -1 (-1800 5825)(-1800 5675);
WIRE 16 -1 (-2075 5825)(-1800 5825);
WIRE 16 -1 (-2075 5825)(-2075 5675);
WIRE 16 -1 (-2325 5825)(-2075 5825);
WIRE 16 -1 (-2325 5675)(-2325 5825);
WIRE 16 -1 (-2600 5825)(-2325 5825);
WIRE 16 -1 (-2600 5825)(-2600 5675);
WIRE 16 -1 (-2600 5825)(-2900 5825);
WIRE 16 -1 (-2900 5825)(-2900 5700);
WIRE 16 -1 (-2900 5825)(-3200 5825);
WIRE 16 -1 (-3200 5825)(-3200 5700);
WIRE 16 -1 (-3500 5825)(-3200 5825);
WIRE 16 -1 (-3500 5825)(-3500 5700);
WIRE 16 -1 (-3825 5825)(-3500 5825);
WIRE 16 -1 (-3825 5825)(-3825 5725);
WIRE 16 -1 (-3825 5825)(-4100 5825);
WIRE 16 -1 (-4100 5825)(-4100 5725);
WIRE 16 -1 (-4200 5825)(-4100 5825);
WIRE 16 -1 (-4250 5825)(-4200 5825);
WIRE 16 -1 (-4200 5825)(-4200 5200);
WIRE 16 -1 (-4200 5200)(-1575 5200);
WIRE 16 -1 (-4250 6050)(-4250 5825);
WIRE 16 -1 (-4250 4575)(-4250 5825);
WIRE 16 -1 (-3875 4575)(-4250 4575);
WIRE 16 -1 (-4250 4575)(-4250 3000);
WIRE 16 -1 (-1575 5200)(-1275 5200);
WIRE 16 -1 (-1575 5100)(-1575 5200);
WIRE 16 -1 (-1275 5200)(-1025 5200);
WIRE 16 -1 (-1275 5100)(-1275 5200);
WIRE 16 -1 (-1025 5200)(-800 5200);
WIRE 16 -1 (-1025 5100)(-1025 5200);
WIRE 16 -1 (-800 5200)(-550 5200);
WIRE 16 -1 (-800 5100)(-800 5200);
WIRE 16 -1 (-550 5200)(-550 5100);
WIRE 16 -1 (-1575 4900)(-1575 4750);
WIRE 16 -1 (-1575 4750)(-1275 4750);
WIRE 16 -1 (-1275 4900)(-1275 4750);
WIRE 16 -1 (-1275 4750)(-1025 4750);
WIRE 16 -1 (-1025 4750)(-800 4750);
WIRE 16 -1 (-1025 4900)(-1025 4750);
WIRE 16 -1 (-800 4750)(-550 4750);
WIRE 16 -1 (-800 4900)(-800 4750);
WIRE 16 -1 (-550 4750)(-225 4750);
WIRE 16 -1 (-550 4900)(-550 4750);
WIRE 16 -1 (-225 5275)(-225 4750);
WIRE 16 -1 (-225 4750)(-225 4650);
WIRE 16 -1 (-225 5275)(-500 5275);
WIRE 16 -1 (-500 5475)(-500 5275);
WIRE 16 -1 (-500 5275)(-900 5275);
WIRE 16 -1 (-900 5500)(-900 5275);
WIRE 16 -1 (-1200 5275)(-900 5275);
WIRE 16 -1 (-1200 5500)(-1200 5275);
WIRE 16 -1 (-1200 5275)(-1500 5275);
WIRE 16 -1 (-1500 5500)(-1500 5275);
WIRE 16 -1 (-1500 5275)(-1800 5275);
WIRE 16 -1 (-1800 5475)(-1800 5275);
WIRE 16 -1 (-2075 5275)(-1800 5275);
WIRE 16 -1 (-2075 5475)(-2075 5275);
WIRE 16 -1 (-2325 5275)(-2075 5275);
WIRE 16 -1 (-2325 5475)(-2325 5275);
WIRE 16 -1 (-2600 5275)(-2325 5275);
WIRE 16 -1 (-2600 5475)(-2600 5275);
WIRE 16 -1 (-2600 5275)(-2900 5275);
WIRE 16 -1 (-2900 5500)(-2900 5275);
WIRE 16 -1 (-2900 5275)(-3200 5275);
WIRE 16 -1 (-3200 5500)(-3200 5275);
WIRE 16 -1 (-3500 5275)(-3200 5275);
WIRE 16 -1 (-3500 5500)(-3500 5275);
WIRE 16 -1 (-3500 5275)(-3825 5275);
WIRE 16 -1 (-3825 5525)(-3825 5275);
WIRE 16 -1 (-4100 5275)(-3825 5275);
WIRE 16 -1 (-4100 5525)(-4100 5275);
WIRE 16 -1 (-5100 4575)(-5100 4425);
WIRE 16 -1 (-5100 4575)(-5375 4575);
WIRE 16 -1 (-5375 4575)(-5375 4425);
WIRE 16 -1 (-5375 4575)(-5625 4575);
WIRE 16 -1 (-5625 4575)(-5625 4425);
WIRE 16 -1 (-5625 4575)(-5875 4575);
WIRE 16 -1 (-5875 4575)(-5875 4425);
WIRE 16 -1 (-6100 4575)(-5875 4575);
WIRE 16 -1 (-6100 4575)(-6100 4425);
WIRE 16 -1 (-6100 4575)(-6300 4575);
WIRE 16 -1 (-6300 4575)(-6300 4425);
WIRE 16 -1 (-6300 4575)(-6525 4575);
WIRE 16 -1 (-6525 4575)(-6525 4425);
WIRE 16 -1 (-6725 4575)(-6525 4575);
WIRE 16 -1 (-6725 4575)(-6725 4425);
WIRE 16 -1 (-6725 4575)(-6925 4575);
WIRE 16 -1 (-6925 4575)(-6925 4425);
WIRE 16 -1 (-7150 4575)(-6925 4575);
WIRE 16 -1 (-7150 4575)(-7150 4425);
WIRE 16 -1 (-7150 4575)(-7250 4575);
WIRE 16 -1 (-7250 4750)(-7250 4575);
WIRE 16 -1 (-7250 4575)(-7625 4575);
WIRE 16 -1 (-7250 3800)(-7250 4575);
WIRE 16 -1 (-7350 3800)(-7250 3800);
WIRE 16 -1 (-7350 3900)(-7350 3800);
WIRE 16 -1 (-7350 3800)(-7350 3700);
WIRE 16 -1 (-7550 3700)(-7350 3700);
WIRE 16 -1 (-7550 3900)(-7350 3900);
WIRE 16 -1 (-5100 4225)(-5100 4125);
WIRE 16 -1 (-5375 4125)(-5100 4125);
WIRE 16 -1 (-5375 4225)(-5375 4125);
WIRE 16 -1 (-5625 4125)(-5375 4125);
WIRE 16 -1 (-5625 4225)(-5625 4125);
WIRE 16 -1 (-5875 4125)(-5625 4125);
WIRE 16 -1 (-5875 4225)(-5875 4125);
WIRE 16 -1 (-6100 4125)(-5875 4125);
WIRE 16 -1 (-6300 4125)(-6100 4125);
WIRE 16 -1 (-6100 4225)(-6100 4125);
WIRE 16 -1 (-6100 4125)(-6100 4050);
WIRE 16 -1 (-6300 4225)(-6300 4125);
WIRE 16 -1 (-6525 4125)(-6300 4125);
WIRE 16 -1 (-6525 4225)(-6525 4125);
WIRE 16 -1 (-6725 4125)(-6525 4125);
WIRE 16 -1 (-6725 4225)(-6725 4125);
WIRE 16 -1 (-6925 4125)(-6725 4125);
WIRE 16 -1 (-6925 4225)(-6925 4125);
WIRE 16 -1 (-7150 4125)(-6925 4125);
WIRE 16 -1 (-7150 4225)(-7150 4125);
WIRE 16 -1 (-8100 4425)(-8050 4425);
WIRE 16 -1 (-8100 4575)(-8100 4425);
WIRE 16 -1 (-8100 4425)(-8150 4425);
WIRE 16 -1 (-8050 4425)(-8050 4325);
WIRE 16 -1 (-8150 4425)(-8150 4350);
WIRE 16 -1 (-8100 5300)(-8100 4575);
WIRE 16 -1 (-8100 4575)(-7825 4575);
WIRE 16 -1 (-7000 5300)(-8100 5300);
WIRE 16 -1 (-8100 5375)(-8100 5300);
WIRE 16 -1 (-7000 5300)(-6750 5300);
WIRE 16 -1 (-7000 5300)(-7000 5250);
WIRE 16 -1 (-6750 5300)(-6500 5300);
WIRE 16 -1 (-6750 5300)(-6750 5250);
WIRE 16 -1 (-6500 5300)(-6250 5300);
WIRE 16 -1 (-6500 5300)(-6500 5225);
WIRE 16 -1 (-6250 5300)(-6250 5225);
WIRE 16 -1 (-6250 5025)(-6250 4900);
WIRE 16 -1 (-6325 4900)(-6250 4900);
WIRE 16 -1 (-6500 4900)(-6325 4900);
WIRE 16 -1 (-6500 5025)(-6500 4900);
WIRE 16 -1 (-6750 4900)(-6500 4900);
WIRE 16 -1 (-6750 5050)(-6750 4900);
WIRE 16 -1 (-7000 4900)(-6750 4900);
WIRE 16 -1 (-7000 5050)(-7000 4900);
WIRE 16 -1 (-2175 1375)(-2175 1525);
WIRE 16 -1 (-2175 1525)(-2425 1525);
WIRE 16 -1 (-2425 1375)(-2425 1525);
WIRE 16 -1 (-2425 1525)(-2725 1525);
WIRE 16 -1 (-2725 1525)(-2725 1375);
WIRE 16 -1 (-2725 1525)(-2975 1525);
WIRE 16 -1 (-2975 1525)(-2975 1375);
WIRE 16 -1 (-2975 1525)(-3100 1525);
WIRE 16 -1 (-3100 1750)(-3100 1525);
WIRE 16 -1 (-4250 1525)(-3100 1525);
WIRE 16 -1 (-4250 1525)(-4250 2625);
WIRE 16 -1 (-4250 2625)(-3975 2625);
WIRE 16 -1 (-4250 2800)(-4250 2625);
WIRE 16 -1 (-2975 1175)(-2975 1050);
WIRE 16 -1 (-2975 1050)(-2725 1050);
WIRE 16 -1 (-2725 1050)(-2425 1050);
WIRE 16 -1 (-2725 1175)(-2725 1050);
WIRE 16 -1 (-2425 1050)(-2275 1050);
WIRE 16 -1 (-2425 1175)(-2425 1050);
WIRE 16 -1 (-2175 1050)(-2275 1050);
WIRE 16 -1 (-2275 1050)(-2275 1000);
WIRE 16 -1 (-2175 1175)(-2175 1050);
WIRE 16 -1 (-425 2300)(-425 2150);
WIRE 16 -1 (-425 2150)(-725 2150);
WIRE 16 -1 (-725 2300)(-725 2150);
WIRE 16 -1 (-725 2150)(-1025 2150);
WIRE 16 -1 (-1025 2300)(-1025 2150);
WIRE 16 -1 (-1025 2150)(-1325 2150);
WIRE 16 -1 (-1575 2150)(-1325 2150);
WIRE 16 -1 (-1325 2275)(-1325 2150);
WIRE 16 -1 (-1325 2150)(-1325 2000);
WIRE 16 -1 (-1575 2275)(-1575 2150);
WIRE 16 -1 (-1575 2150)(-1850 2150);
WIRE 16 -1 (-1850 2275)(-1850 2150);
WIRE 16 -1 (-2125 2150)(-1850 2150);
WIRE 16 -1 (-2125 2275)(-2125 2150);
WIRE 16 -1 (-2375 2150)(-2125 2150);
WIRE 16 -1 (-2375 2275)(-2375 2150);
WIRE 16 -1 (-2625 2150)(-2375 2150);
WIRE 16 -1 (-2625 2275)(-2625 2150);
WIRE 16 -1 (-2850 2150)(-2625 2150);
WIRE 16 -1 (-2850 2275)(-2850 2150);
WIRE 16 -1 (-3150 2150)(-2850 2150);
WIRE 16 -1 (-3150 2275)(-3150 2150);
WIRE 16 -1 (-6725 3150)(-6725 2975);
WIRE 16 -1 (-6725 2975)(-6450 2975);
WIRE 16 -1 (-6450 3125)(-6450 2975);
WIRE 16 -1 (-6450 2975)(-6450 2875);
WIRE 16 -1 (-6450 3475)(-6450 3325);
WIRE 16 -1 (-6725 3475)(-6450 3475);
WIRE 16 -1 (-6725 3350)(-6725 3475);
WIRE 16 -1 (-6725 3475)(-6850 3475);
WIRE 16 -1 (-8100 3475)(-6850 3475);
WIRE 16 -1 (-6850 3475)(-6850 3575);
WIRE 16 -1 (-8100 3475)(-8100 3800);
WIRE 16 -1 (-8100 3800)(-8100 3975);
WIRE 16 -1 (-8100 3800)(-8000 3800);
WIRE 16 -1 (-8000 3900)(-8000 3800);
WIRE 16 -1 (-8000 3800)(-8000 3700);
WIRE 16 -1 (-8100 3975)(-8050 3975);
WIRE 16 -1 (-8150 3975)(-8100 3975);
WIRE 16 -1 (-8150 3975)(-8150 4150);
WIRE 16 -1 (-8050 3975)(-8050 4125);
WIRE 16 -1 (-8000 3700)(-7750 3700);
WIRE 16 -1 (-7750 3900)(-8000 3900);
DOT 1 (-1275 5200);
DOT 1 (-1200 5275);
DOT 1 (-500 5275);
DOT 1 (-550 4750);
DOT 1 (-800 4750);
DOT 1 (-800 5200);
DOT 1 (-1025 4750);
DOT 1 (-1025 5200);
DOT 1 (-1275 4750);
DOT 1 (-1575 5200);
DOT 1 (-225 4750);
DOT 1 (-4200 5825);
DOT 1 (-3200 5275);
DOT 1 (-3825 5825);
DOT 1 (-4100 5825);
DOT 1 (-4250 5825);
DOT 1 (-1825 4575);
DOT 1 (-1800 5825);
DOT 1 (-1500 5275);
DOT 1 (-1500 5825);
DOT 1 (-1200 5825);
DOT 1 (-900 5275);
DOT 1 (-900 5825);
DOT 1 (-1800 5275);
DOT 1 (-3825 5275);
DOT 1 (-3500 5275);
DOT 1 (-3500 5825);
DOT 1 (-2900 5275);
DOT 1 (-2900 5825);
DOT 1 (-2600 5275);
DOT 1 (-2600 5825);
DOT 1 (-2325 5275);
DOT 1 (-2325 5825);
DOT 1 (-2075 5275);
DOT 1 (-2075 5825);
DOT 1 (-2475 3300);
DOT 1 (-1575 2625);
DOT 1 (-2975 1525);
DOT 1 (-2725 1050);
DOT 1 (-2725 1525);
DOT 1 (-2125 2625);
DOT 1 (-2275 3925);
DOT 1 (-1800 3300);
DOT 1 (-1800 2750);
DOT 1 (-1550 2750);
DOT 1 (-2250 3300);
DOT 1 (-1350 3475);
DOT 1 (-2975 3475);
DOT 1 (-2725 3300);
DOT 1 (-2025 3300);
DOT 1 (-2950 3300);
DOT 1 (-2275 3475);
DOT 1 (-2750 3475);
DOT 1 (-3200 3300);
DOT 1 (-825 3475);
DOT 1 (-1825 3925);
DOT 1 (-1825 3475);
DOT 1 (-2375 2625);
DOT 1 (-2750 3925);
DOT 1 (-2725 2750);
DOT 1 (-2850 2625);
DOT 1 (-1525 4075);
DOT 1 (-2050 4575);
DOT 1 (-1525 4575);
DOT 1 (-3200 4575);
DOT 1 (-3425 3925);
DOT 1 (-2500 4575);
DOT 1 (-2275 4075);
DOT 1 (-1600 3925);
DOT 1 (-2500 3925);
DOT 1 (-2475 2750);
DOT 1 (-1600 3475);
DOT 1 (-2750 4575);
DOT 1 (-2975 4575);
DOT 1 (-3425 4575);
DOT 1 (-5375 4125);
DOT 1 (-6100 4125);
DOT 1 (-6100 4575);
DOT 1 (-6750 4900);
DOT 1 (-8000 3800);
DOT 1 (-8100 3800);
DOT 1 (-8100 3975);
DOT 1 (-6450 2975);
DOT 1 (-6850 3475);
DOT 1 (-6725 3475);
DOT 1 (-6925 4125);
DOT 1 (-6725 4125);
DOT 1 (-6525 4125);
DOT 1 (-6300 4125);
DOT 1 (-5875 4125);
DOT 1 (-5625 4125);
DOT 1 (-4250 2625);
DOT 1 (-8100 5300);
DOT 1 (-7250 4575);
DOT 1 (-7150 4575);
DOT 1 (-6925 4575);
DOT 1 (-6725 4575);
DOT 1 (-7000 5300);
DOT 1 (-6750 5300);
DOT 1 (-6525 4575);
DOT 1 (-6500 4900);
DOT 1 (-6300 4575);
DOT 1 (-6500 5300);
DOT 1 (-5875 4575);
DOT 1 (-5625 4575);
DOT 1 (-5375 4575);
DOT 1 (-4250 4575);
DOT 1 (-3100 1525);
DOT 1 (-2425 1050);
DOT 1 (-2275 1050);
DOT 1 (-2850 2150);
DOT 1 (-2625 2150);
DOT 1 (-2425 1525);
DOT 1 (-2375 2150);
DOT 1 (-2125 2150);
DOT 1 (-3600 2625);
DOT 1 (-3600 3300);
DOT 1 (-3150 2625);
DOT 1 (-3200 2750);
DOT 1 (-3425 3300);
DOT 1 (-3600 3925);
DOT 1 (-3200 3925);
DOT 1 (-2950 2750);
DOT 1 (-2625 2625);
DOT 1 (-2975 4075);
DOT 1 (-2975 3925);
DOT 1 (-2500 4075);
DOT 1 (-1850 2150);
DOT 1 (-1575 2150);
DOT 1 (-1850 2625);
DOT 1 (-1825 4075);
DOT 1 (-1225 4075);
DOT 1 (-825 2750);
DOT 1 (-3600 4575);
DOT 1 (-2025 2750);
DOT 1 (-8100 4575);
DOT 1 (-7350 3800);
DOT 1 (-3200 4075);
DOT 1 (-3200 3475);
DOT 1 (-2750 4075);
DOT 1 (-2500 3475);
DOT 1 (-8100 4425);
DOT 1 (-3200 5825);
DOT 1 (-2250 2750);
DOT 1 (-2275 4575);
DOT 1 (-2050 4075);
DOT 1 (-2050 3925);
DOT 1 (-2050 3475);
DOT 1 (-1325 2625);
DOT 1 (-1325 2150);
DOT 1 (-725 2625);
DOT 1 (-725 2150);
DOT 1 (-1025 2625);
DOT 1 (-1025 2150);
QUIT
